FILE_TYPE = MACRO_DRAWING;
SET COLOR_WIRE YELLOW;
SET COLOR_PROP ORANGE;
SET COLOR_DOT WHITE;
SET COLOR_ARC YELLOW;
SET COLOR_BODY GREEN;
SET COLOR_NOTE PURPLE;
SET PROP_DISPLAY VALUE;
SET PAGE_NUMBER P19;
FORCEADD GENOA_SP5..10
(-4525 3625);
FORCEPROP 1 LAST LOCATION U25
J 0
(-5170 6456);
DISPLAY 0.489362 (-5170 6456);
PAINT SKYBLUE (-5170 6456);
FORCEPROP 0 LAST $SEC 10
J 0
(-5150 6500);
DISPLAY 0.680851 (-5150 6500);
PAINT MONO (-5150 6500);
DISPLAY INVISIBLE (-5150 6500);
FORCEPROP 0 LAST CDS_SEC 10
J 0
(-5175 6425);
DISPLAY 1.021277 (-5175 6425);
DISPLAY INVISIBLE (-5175 6425);
FORCEPROP 0 LASTPIN (-5325 3000) $PN BC16
J 2
(-5335 3010);
DISPLAY 0.489362 (-5335 3010);
PAINT MONO (-5335 3010);
FORCEPROP 0 LASTPIN (-5325 2950) $PN BD16
J 2
(-5335 2960);
DISPLAY 0.489362 (-5335 2960);
PAINT MONO (-5335 2960);
FORCEPROP 0 LASTPIN (-5325 1850) $PN BF16
J 2
(-5335 1860);
DISPLAY 0.489362 (-5335 1860);
PAINT MONO (-5335 1860);
FORCEPROP 0 LASTPIN (-5325 1800) $PN BG16
J 2
(-5335 1810);
DISPLAY 0.489362 (-5335 1810);
PAINT MONO (-5335 1810);
FORCEPROP 0 LASTPIN (-5325 2150) $PN AT18
J 2
(-5335 2160);
DISPLAY 0.489362 (-5335 2160);
PAINT MONO (-5335 2160);
FORCEPROP 0 LASTPIN (-5325 2050) $PN AU17
J 2
(-5335 2060);
DISPLAY 0.489362 (-5335 2060);
PAINT MONO (-5335 2060);
FORCEPROP 0 LASTPIN (-5325 2850) $PN AU16
J 2
(-5335 2860);
DISPLAY 0.489362 (-5335 2860);
PAINT MONO (-5335 2860);
FORCEPROP 0 LASTPIN (-5325 2800) $PN AV18
J 2
(-5335 2810);
DISPLAY 0.489362 (-5335 2810);
PAINT MONO (-5335 2810);
FORCEPROP 0 LASTPIN (-5325 2700) $PN BN17
J 2
(-5335 2710);
DISPLAY 0.489362 (-5335 2710);
PAINT MONO (-5335 2710);
FORCEPROP 0 LASTPIN (-5325 1700) $PN AV16
J 2
(-5335 1710);
DISPLAY 0.489362 (-5335 1710);
PAINT MONO (-5335 1710);
FORCEPROP 0 LASTPIN (-5325 1650) $PN AW17
J 2
(-5335 1660);
DISPLAY 0.489362 (-5335 1660);
PAINT MONO (-5335 1660);
FORCEPROP 0 LASTPIN (-5325 1550) $PN BP18
J 2
(-5335 1560);
DISPLAY 0.489362 (-5335 1560);
PAINT MONO (-5335 1560);
FORCEPROP 0 LASTPIN (-5325 3850) $PN AW16
J 2
(-5335 3860);
DISPLAY 0.489362 (-5335 3860);
PAINT MONO (-5335 3860);
FORCEPROP 0 LASTPIN (-5325 3800) $PN AY16
J 2
(-5335 3810);
DISPLAY 0.489362 (-5335 3810);
PAINT MONO (-5335 3810);
FORCEPROP 0 LASTPIN (-5325 3750) $PN AY18
J 2
(-5335 3760);
DISPLAY 0.489362 (-5335 3760);
PAINT MONO (-5335 3760);
FORCEPROP 0 LASTPIN (-5325 3700) $PN BA17
J 2
(-5335 3710);
DISPLAY 0.489362 (-5335 3710);
PAINT MONO (-5335 3710);
FORCEPROP 0 LASTPIN (-5325 3650) $PN BA16
J 2
(-5335 3660);
DISPLAY 0.489362 (-5335 3660);
PAINT MONO (-5335 3660);
FORCEPROP 0 LASTPIN (-5325 3600) $PN BB16
J 2
(-5335 3610);
DISPLAY 0.489362 (-5335 3610);
PAINT MONO (-5335 3610);
FORCEPROP 0 LASTPIN (-5325 3550) $PN BB18
J 2
(-5335 3560);
DISPLAY 0.489362 (-5335 3560);
PAINT MONO (-5335 3560);
FORCEPROP 0 LASTPIN (-3725 2400) $PN AJ16
J 0
(-3715 2410);
DISPLAY 0.489362 (-3715 2410);
PAINT MONO (-3715 2410);
FORCEPROP 0 LASTPIN (-3725 2350) $PN AK18
J 0
(-3715 2360);
DISPLAY 0.489362 (-3715 2360);
PAINT MONO (-3715 2360);
FORCEPROP 0 LASTPIN (-3725 2300) $PN AK16
J 0
(-3715 2310);
DISPLAY 0.489362 (-3715 2310);
PAINT MONO (-3715 2310);
FORCEPROP 0 LASTPIN (-3725 2250) $PN AL17
J 0
(-3715 2260);
DISPLAY 0.489362 (-3715 2260);
PAINT MONO (-3715 2260);
FORCEPROP 0 LASTPIN (-3725 2200) $PN AN16
J 0
(-3715 2210);
DISPLAY 0.489362 (-3715 2210);
PAINT MONO (-3715 2210);
FORCEPROP 0 LASTPIN (-3725 2150) $PN AP18
J 0
(-3715 2160);
DISPLAY 0.489362 (-3715 2160);
PAINT MONO (-3715 2160);
FORCEPROP 0 LASTPIN (-3725 2100) $PN AP16
J 0
(-3715 2110);
DISPLAY 0.489362 (-3715 2110);
PAINT MONO (-3715 2110);
FORCEPROP 0 LASTPIN (-3725 2050) $PN AR17
J 0
(-3715 2060);
DISPLAY 0.489362 (-3715 2060);
PAINT MONO (-3715 2060);
FORCEPROP 0 LASTPIN (-3725 6000) $PN E16
J 0
(-3715 6010);
DISPLAY 0.489362 (-3715 6010);
PAINT MONO (-3715 6010);
FORCEPROP 0 LASTPIN (-3725 5950) $PN F18
J 0
(-3715 5960);
DISPLAY 0.489362 (-3715 5960);
PAINT MONO (-3715 5960);
FORCEPROP 0 LASTPIN (-3725 5900) $PN F16
J 0
(-3715 5910);
DISPLAY 0.489362 (-3715 5910);
PAINT MONO (-3715 5910);
FORCEPROP 0 LASTPIN (-3725 5850) $PN G17
J 0
(-3715 5860);
DISPLAY 0.489362 (-3715 5860);
PAINT MONO (-3715 5860);
FORCEPROP 0 LASTPIN (-3725 5800) $PN J16
J 0
(-3715 5810);
DISPLAY 0.489362 (-3715 5810);
PAINT MONO (-3715 5810);
FORCEPROP 0 LASTPIN (-3725 5750) $PN K18
J 0
(-3715 5760);
DISPLAY 0.489362 (-3715 5760);
PAINT MONO (-3715 5760);
FORCEPROP 0 LASTPIN (-3725 5700) $PN K16
J 0
(-3715 5710);
DISPLAY 0.489362 (-3715 5710);
PAINT MONO (-3715 5710);
FORCEPROP 0 LASTPIN (-3725 5650) $PN L17
J 0
(-3715 5660);
DISPLAY 0.489362 (-3715 5660);
PAINT MONO (-3715 5660);
FORCEPROP 0 LASTPIN (-3725 5550) $PN L16
J 0
(-3715 5560);
DISPLAY 0.489362 (-3715 5560);
PAINT MONO (-3715 5560);
FORCEPROP 0 LASTPIN (-3725 5500) $PN M18
J 0
(-3715 5510);
DISPLAY 0.489362 (-3715 5510);
PAINT MONO (-3715 5510);
FORCEPROP 0 LASTPIN (-3725 5450) $PN M16
J 0
(-3715 5460);
DISPLAY 0.489362 (-3715 5460);
PAINT MONO (-3715 5460);
FORCEPROP 0 LASTPIN (-3725 5400) $PN N17
J 0
(-3715 5410);
DISPLAY 0.489362 (-3715 5410);
PAINT MONO (-3715 5410);
FORCEPROP 0 LASTPIN (-3725 5350) $PN R16
J 0
(-3715 5360);
DISPLAY 0.489362 (-3715 5360);
PAINT MONO (-3715 5360);
FORCEPROP 0 LASTPIN (-3725 5300) $PN T18
J 0
(-3715 5310);
DISPLAY 0.489362 (-3715 5310);
PAINT MONO (-3715 5310);
FORCEPROP 0 LASTPIN (-3725 5250) $PN T16
J 0
(-3715 5260);
DISPLAY 0.489362 (-3715 5260);
PAINT MONO (-3715 5260);
FORCEPROP 0 LASTPIN (-3725 5200) $PN U17
J 0
(-3715 5210);
DISPLAY 0.489362 (-3715 5210);
PAINT MONO (-3715 5210);
FORCEPROP 0 LASTPIN (-3725 5100) $PN U16
J 0
(-3715 5110);
DISPLAY 0.489362 (-3715 5110);
PAINT MONO (-3715 5110);
FORCEPROP 0 LASTPIN (-3725 5050) $PN V18
J 0
(-3715 5060);
DISPLAY 0.489362 (-3715 5060);
PAINT MONO (-3715 5060);
FORCEPROP 0 LASTPIN (-3725 5000) $PN V16
J 0
(-3715 5010);
DISPLAY 0.489362 (-3715 5010);
PAINT MONO (-3715 5010);
FORCEPROP 0 LASTPIN (-3725 4950) $PN W17
J 0
(-3715 4960);
DISPLAY 0.489362 (-3715 4960);
PAINT MONO (-3715 4960);
FORCEPROP 0 LASTPIN (-3725 4900) $PN AA16
J 0
(-3715 4910);
DISPLAY 0.489362 (-3715 4910);
PAINT MONO (-3715 4910);
FORCEPROP 0 LASTPIN (-3725 4850) $PN AB18
J 0
(-3715 4860);
DISPLAY 0.489362 (-3715 4860);
PAINT MONO (-3715 4860);
FORCEPROP 0 LASTPIN (-3725 4800) $PN AB16
J 0
(-3715 4810);
DISPLAY 0.489362 (-3715 4810);
PAINT MONO (-3715 4810);
FORCEPROP 0 LASTPIN (-3725 4750) $PN AC17
J 0
(-3715 4760);
DISPLAY 0.489362 (-3715 4760);
PAINT MONO (-3715 4760);
FORCEPROP 0 LASTPIN (-3725 4650) $PN AC16
J 0
(-3715 4660);
DISPLAY 0.489362 (-3715 4660);
PAINT MONO (-3715 4660);
FORCEPROP 0 LASTPIN (-3725 4600) $PN AD18
J 0
(-3715 4610);
DISPLAY 0.489362 (-3715 4610);
PAINT MONO (-3715 4610);
FORCEPROP 0 LASTPIN (-3725 4550) $PN AD16
J 0
(-3715 4560);
DISPLAY 0.489362 (-3715 4560);
PAINT MONO (-3715 4560);
FORCEPROP 0 LASTPIN (-3725 4500) $PN AE17
J 0
(-3715 4510);
DISPLAY 0.489362 (-3715 4510);
PAINT MONO (-3715 4510);
FORCEPROP 0 LASTPIN (-3725 4450) $PN AG16
J 0
(-3715 4460);
DISPLAY 0.489362 (-3715 4460);
PAINT MONO (-3715 4460);
FORCEPROP 0 LASTPIN (-3725 4400) $PN AH18
J 0
(-3715 4410);
DISPLAY 0.489362 (-3715 4410);
PAINT MONO (-3715 4410);
FORCEPROP 0 LASTPIN (-3725 4350) $PN AH16
J 0
(-3715 4360);
DISPLAY 0.489362 (-3715 4360);
PAINT MONO (-3715 4360);
FORCEPROP 0 LASTPIN (-3725 4300) $PN AJ17
J 0
(-3715 4310);
DISPLAY 0.489362 (-3715 4310);
PAINT MONO (-3715 4310);
FORCEPROP 0 LASTPIN (-5325 6000) $PN G16
J 2
(-5335 6010);
DISPLAY 0.489362 (-5335 6010);
PAINT MONO (-5335 6010);
FORCEPROP 0 LASTPIN (-5325 5900) $PN N16
J 2
(-5335 5910);
DISPLAY 0.489362 (-5335 5910);
PAINT MONO (-5335 5910);
FORCEPROP 0 LASTPIN (-5325 5800) $PN W16
J 2
(-5335 5810);
DISPLAY 0.489362 (-5335 5810);
PAINT MONO (-5335 5810);
FORCEPROP 0 LASTPIN (-5325 5700) $PN AE16
J 2
(-5335 5710);
DISPLAY 0.489362 (-5335 5710);
PAINT MONO (-5335 5710);
FORCEPROP 0 LASTPIN (-5325 5600) $PN AL16
J 2
(-5335 5610);
DISPLAY 0.489362 (-5335 5610);
PAINT MONO (-5335 5610);
FORCEPROP 0 LASTPIN (-5325 5500) $PN J17
J 2
(-5335 5510);
DISPLAY 0.489362 (-5335 5510);
PAINT MONO (-5335 5510);
FORCEPROP 0 LASTPIN (-5325 5400) $PN R17
J 2
(-5335 5410);
DISPLAY 0.489362 (-5335 5410);
PAINT MONO (-5335 5410);
FORCEPROP 0 LASTPIN (-5325 5300) $PN AA17
J 2
(-5335 5310);
DISPLAY 0.489362 (-5335 5310);
PAINT MONO (-5335 5310);
FORCEPROP 0 LASTPIN (-5325 5200) $PN AG17
J 2
(-5335 5210);
DISPLAY 0.489362 (-5335 5210);
PAINT MONO (-5335 5210);
FORCEPROP 0 LASTPIN (-5325 5100) $PN AN17
J 2
(-5335 5110);
DISPLAY 0.489362 (-5335 5110);
PAINT MONO (-5335 5110);
FORCEPROP 0 LASTPIN (-5325 5950) $PN H16
J 2
(-5335 5960);
DISPLAY 0.489362 (-5335 5960);
PAINT MONO (-5335 5960);
FORCEPROP 0 LASTPIN (-5325 5850) $PN P16
J 2
(-5335 5860);
DISPLAY 0.489362 (-5335 5860);
PAINT MONO (-5335 5860);
FORCEPROP 0 LASTPIN (-5325 5750) $PN Y16
J 2
(-5335 5760);
DISPLAY 0.489362 (-5335 5760);
PAINT MONO (-5335 5760);
FORCEPROP 0 LASTPIN (-5325 5650) $PN AF16
J 2
(-5335 5660);
DISPLAY 0.489362 (-5335 5660);
PAINT MONO (-5335 5660);
FORCEPROP 0 LASTPIN (-5325 5550) $PN AM16
J 2
(-5335 5560);
DISPLAY 0.489362 (-5335 5560);
PAINT MONO (-5335 5560);
FORCEPROP 0 LASTPIN (-5325 5450) $PN H18
J 2
(-5335 5460);
DISPLAY 0.489362 (-5335 5460);
PAINT MONO (-5335 5460);
FORCEPROP 0 LASTPIN (-5325 5350) $PN P18
J 2
(-5335 5360);
DISPLAY 0.489362 (-5335 5360);
PAINT MONO (-5335 5360);
FORCEPROP 0 LASTPIN (-5325 5250) $PN Y18
J 2
(-5335 5260);
DISPLAY 0.489362 (-5335 5260);
PAINT MONO (-5335 5260);
FORCEPROP 0 LASTPIN (-5325 5150) $PN AF18
J 2
(-5335 5160);
DISPLAY 0.489362 (-5335 5160);
PAINT MONO (-5335 5160);
FORCEPROP 0 LASTPIN (-5325 5050) $PN AM18
J 2
(-5335 5060);
DISPLAY 0.489362 (-5335 5060);
PAINT MONO (-5335 5060);
FORCEPROP 0 LASTPIN (-5325 2600) $PN BC17
J 2
(-5335 2610);
DISPLAY 0.489362 (-5335 2610);
PAINT MONO (-5335 2610);
FORCEPROP 0 LASTPIN (-5325 2500) $PN BM18
J 2
(-5335 2510);
DISPLAY 0.489362 (-5335 2510);
PAINT MONO (-5335 2510);
FORCEPROP 0 LASTPIN (-5325 2450) $PN BN16
J 2
(-5335 2460);
DISPLAY 0.489362 (-5335 2460);
PAINT MONO (-5335 2460);
FORCEPROP 0 LASTPIN (-5325 2350) $PN BP16
J 2
(-5335 2360);
DISPLAY 0.489362 (-5335 2360);
PAINT MONO (-5335 2360);
FORCEPROP 0 LASTPIN (-5325 1450) $PN BL16
J 2
(-5335 1460);
DISPLAY 0.489362 (-5335 1460);
PAINT MONO (-5335 1460);
FORCEPROP 0 LASTPIN (-5325 1400) $PN BM16
J 2
(-5335 1410);
DISPLAY 0.489362 (-5335 1410);
PAINT MONO (-5335 1410);
FORCEPROP 0 LASTPIN (-5325 1300) $PN BR16
J 2
(-5335 1310);
DISPLAY 0.489362 (-5335 1310);
PAINT MONO (-5335 1310);
FORCEPROP 0 LASTPIN (-5325 3450) $PN BG17
J 2
(-5335 3460);
DISPLAY 0.489362 (-5335 3460);
PAINT MONO (-5335 3460);
FORCEPROP 0 LASTPIN (-5325 3400) $PN BH18
J 2
(-5335 3410);
DISPLAY 0.489362 (-5335 3410);
PAINT MONO (-5335 3410);
FORCEPROP 0 LASTPIN (-5325 3350) $PN BH16
J 2
(-5335 3360);
DISPLAY 0.489362 (-5335 3360);
PAINT MONO (-5335 3360);
FORCEPROP 0 LASTPIN (-5325 3300) $PN BJ16
J 2
(-5335 3310);
DISPLAY 0.489362 (-5335 3310);
PAINT MONO (-5335 3310);
FORCEPROP 0 LASTPIN (-5325 3250) $PN BJ17
J 2
(-5335 3260);
DISPLAY 0.489362 (-5335 3260);
PAINT MONO (-5335 3260);
FORCEPROP 0 LASTPIN (-5325 3200) $PN BK18
J 2
(-5335 3210);
DISPLAY 0.489362 (-5335 3210);
PAINT MONO (-5335 3210);
FORCEPROP 0 LASTPIN (-5325 3150) $PN BK16
J 2
(-5335 3160);
DISPLAY 0.489362 (-5335 3160);
PAINT MONO (-5335 3160);
FORCEPROP 0 LASTPIN (-3725 1950) $PN BY16
J 0
(-3715 1960);
DISPLAY 0.489362 (-3715 1960);
PAINT MONO (-3715 1960);
FORCEPROP 0 LASTPIN (-3725 1900) $PN CA17
J 0
(-3715 1910);
DISPLAY 0.489362 (-3715 1910);
PAINT MONO (-3715 1910);
FORCEPROP 0 LASTPIN (-3725 1850) $PN CA16
J 0
(-3715 1860);
DISPLAY 0.489362 (-3715 1860);
PAINT MONO (-3715 1860);
FORCEPROP 0 LASTPIN (-3725 1800) $PN CB18
J 0
(-3715 1810);
DISPLAY 0.489362 (-3715 1810);
PAINT MONO (-3715 1810);
FORCEPROP 0 LASTPIN (-3725 1750) $PN BT16
J 0
(-3715 1760);
DISPLAY 0.489362 (-3715 1760);
PAINT MONO (-3715 1760);
FORCEPROP 0 LASTPIN (-3725 1700) $PN BU17
J 0
(-3715 1710);
DISPLAY 0.489362 (-3715 1710);
PAINT MONO (-3715 1710);
FORCEPROP 0 LASTPIN (-3725 1650) $PN BU16
J 0
(-3715 1660);
DISPLAY 0.489362 (-3715 1660);
PAINT MONO (-3715 1660);
FORCEPROP 0 LASTPIN (-3725 1600) $PN BV18
J 0
(-3715 1610);
DISPLAY 0.489362 (-3715 1610);
PAINT MONO (-3715 1610);
FORCEPROP 0 LASTPIN (-3725 4200) $PN CB16
J 0
(-3715 4210);
DISPLAY 0.489362 (-3715 4210);
PAINT MONO (-3715 4210);
FORCEPROP 0 LASTPIN (-3725 4150) $PN CC17
J 0
(-3715 4160);
DISPLAY 0.489362 (-3715 4160);
PAINT MONO (-3715 4160);
FORCEPROP 0 LASTPIN (-3725 4100) $PN CC16
J 0
(-3715 4110);
DISPLAY 0.489362 (-3715 4110);
PAINT MONO (-3715 4110);
FORCEPROP 0 LASTPIN (-3725 4050) $PN CD18
J 0
(-3715 4060);
DISPLAY 0.489362 (-3715 4060);
PAINT MONO (-3715 4060);
FORCEPROP 0 LASTPIN (-3725 4000) $PN CF16
J 0
(-3715 4010);
DISPLAY 0.489362 (-3715 4010);
PAINT MONO (-3715 4010);
FORCEPROP 0 LASTPIN (-3725 3950) $PN CG17
J 0
(-3715 3960);
DISPLAY 0.489362 (-3715 3960);
PAINT MONO (-3715 3960);
FORCEPROP 0 LASTPIN (-3725 3900) $PN CG16
J 0
(-3715 3910);
DISPLAY 0.489362 (-3715 3910);
PAINT MONO (-3715 3910);
FORCEPROP 0 LASTPIN (-3725 3850) $PN CH18
J 0
(-3715 3860);
DISPLAY 0.489362 (-3715 3860);
PAINT MONO (-3715 3860);
FORCEPROP 0 LASTPIN (-3725 3750) $PN CH16
J 0
(-3715 3760);
DISPLAY 0.489362 (-3715 3760);
PAINT MONO (-3715 3760);
FORCEPROP 0 LASTPIN (-3725 3700) $PN CJ17
J 0
(-3715 3710);
DISPLAY 0.489362 (-3715 3710);
PAINT MONO (-3715 3710);
FORCEPROP 0 LASTPIN (-3725 3650) $PN CJ16
J 0
(-3715 3660);
DISPLAY 0.489362 (-3715 3660);
PAINT MONO (-3715 3660);
FORCEPROP 0 LASTPIN (-3725 3600) $PN CK18
J 0
(-3715 3610);
DISPLAY 0.489362 (-3715 3610);
PAINT MONO (-3715 3610);
FORCEPROP 0 LASTPIN (-3725 3550) $PN CM16
J 0
(-3715 3560);
DISPLAY 0.489362 (-3715 3560);
PAINT MONO (-3715 3560);
FORCEPROP 0 LASTPIN (-3725 3500) $PN CN17
J 0
(-3715 3510);
DISPLAY 0.489362 (-3715 3510);
PAINT MONO (-3715 3510);
FORCEPROP 0 LASTPIN (-3725 3450) $PN CN16
J 0
(-3715 3460);
DISPLAY 0.489362 (-3715 3460);
PAINT MONO (-3715 3460);
FORCEPROP 0 LASTPIN (-3725 3400) $PN CP18
J 0
(-3715 3410);
DISPLAY 0.489362 (-3715 3410);
PAINT MONO (-3715 3410);
FORCEPROP 0 LASTPIN (-3725 3300) $PN CP16
J 0
(-3715 3310);
DISPLAY 0.489362 (-3715 3310);
PAINT MONO (-3715 3310);
FORCEPROP 0 LASTPIN (-3725 3250) $PN CR17
J 0
(-3715 3260);
DISPLAY 0.489362 (-3715 3260);
PAINT MONO (-3715 3260);
FORCEPROP 0 LASTPIN (-3725 3200) $PN CR16
J 0
(-3715 3210);
DISPLAY 0.489362 (-3715 3210);
PAINT MONO (-3715 3210);
FORCEPROP 0 LASTPIN (-3725 3150) $PN CT18
J 0
(-3715 3160);
DISPLAY 0.489362 (-3715 3160);
PAINT MONO (-3715 3160);
FORCEPROP 0 LASTPIN (-3725 3100) $PN CV16
J 0
(-3715 3110);
DISPLAY 0.489362 (-3715 3110);
PAINT MONO (-3715 3110);
FORCEPROP 0 LASTPIN (-3725 3050) $PN CW17
J 0
(-3715 3060);
DISPLAY 0.489362 (-3715 3060);
PAINT MONO (-3715 3060);
FORCEPROP 0 LASTPIN (-3725 3000) $PN CW16
J 0
(-3715 3010);
DISPLAY 0.489362 (-3715 3010);
PAINT MONO (-3715 3010);
FORCEPROP 0 LASTPIN (-3725 2950) $PN CY18
J 0
(-3715 2960);
DISPLAY 0.489362 (-3715 2960);
PAINT MONO (-3715 2960);
FORCEPROP 0 LASTPIN (-3725 2850) $PN CY16
J 0
(-3715 2860);
DISPLAY 0.489362 (-3715 2860);
PAINT MONO (-3715 2860);
FORCEPROP 0 LASTPIN (-3725 2800) $PN DA17
J 0
(-3715 2810);
DISPLAY 0.489362 (-3715 2810);
PAINT MONO (-3715 2810);
FORCEPROP 0 LASTPIN (-3725 2750) $PN DA16
J 0
(-3715 2760);
DISPLAY 0.489362 (-3715 2760);
PAINT MONO (-3715 2760);
FORCEPROP 0 LASTPIN (-3725 2700) $PN DB18
J 0
(-3715 2710);
DISPLAY 0.489362 (-3715 2710);
PAINT MONO (-3715 2710);
FORCEPROP 0 LASTPIN (-3725 2650) $PN DD16
J 0
(-3715 2660);
DISPLAY 0.489362 (-3715 2660);
PAINT MONO (-3715 2660);
FORCEPROP 0 LASTPIN (-3725 2600) $PN DE17
J 0
(-3715 2610);
DISPLAY 0.489362 (-3715 2610);
PAINT MONO (-3715 2610);
FORCEPROP 0 LASTPIN (-3725 2550) $PN DE16
J 0
(-3715 2560);
DISPLAY 0.489362 (-3715 2560);
PAINT MONO (-3715 2560);
FORCEPROP 0 LASTPIN (-3725 2500) $PN DF16
J 0
(-3715 2510);
DISPLAY 0.489362 (-3715 2510);
PAINT MONO (-3715 2510);
FORCEPROP 0 LASTPIN (-5325 4950) $PN CD16
J 2
(-5335 4960);
DISPLAY 0.489362 (-5335 4960);
PAINT MONO (-5335 4960);
FORCEPROP 0 LASTPIN (-5325 4850) $PN CK16
J 2
(-5335 4860);
DISPLAY 0.489362 (-5335 4860);
PAINT MONO (-5335 4860);
FORCEPROP 0 LASTPIN (-5325 4750) $PN CT16
J 2
(-5335 4760);
DISPLAY 0.489362 (-5335 4760);
PAINT MONO (-5335 4760);
FORCEPROP 0 LASTPIN (-5325 4650) $PN DB16
J 2
(-5335 4660);
DISPLAY 0.489362 (-5335 4660);
PAINT MONO (-5335 4660);
FORCEPROP 0 LASTPIN (-5325 4550) $PN BY18
J 2
(-5335 4560);
DISPLAY 0.489362 (-5335 4560);
PAINT MONO (-5335 4560);
FORCEPROP 0 LASTPIN (-5325 4450) $PN CF18
J 2
(-5335 4460);
DISPLAY 0.489362 (-5335 4460);
PAINT MONO (-5335 4460);
FORCEPROP 0 LASTPIN (-5325 4350) $PN CM18
J 2
(-5335 4360);
DISPLAY 0.489362 (-5335 4360);
PAINT MONO (-5335 4360);
FORCEPROP 0 LASTPIN (-5325 4250) $PN CV18
J 2
(-5335 4260);
DISPLAY 0.489362 (-5335 4260);
PAINT MONO (-5335 4260);
FORCEPROP 0 LASTPIN (-5325 4150) $PN DD18
J 2
(-5335 4160);
DISPLAY 0.489362 (-5335 4160);
PAINT MONO (-5335 4160);
FORCEPROP 0 LASTPIN (-5325 4050) $PN BV16
J 2
(-5335 4060);
DISPLAY 0.489362 (-5335 4060);
PAINT MONO (-5335 4060);
FORCEPROP 0 LASTPIN (-5325 4900) $PN CE16
J 2
(-5335 4910);
DISPLAY 0.489362 (-5335 4910);
PAINT MONO (-5335 4910);
FORCEPROP 0 LASTPIN (-5325 4800) $PN CL16
J 2
(-5335 4810);
DISPLAY 0.489362 (-5335 4810);
PAINT MONO (-5335 4810);
FORCEPROP 0 LASTPIN (-5325 4700) $PN CU16
J 2
(-5335 4710);
DISPLAY 0.489362 (-5335 4710);
PAINT MONO (-5335 4710);
FORCEPROP 0 LASTPIN (-5325 4600) $PN DC16
J 2
(-5335 4610);
DISPLAY 0.489362 (-5335 4610);
PAINT MONO (-5335 4610);
FORCEPROP 0 LASTPIN (-5325 4500) $PN BW17
J 2
(-5335 4510);
DISPLAY 0.489362 (-5335 4510);
PAINT MONO (-5335 4510);
FORCEPROP 0 LASTPIN (-5325 4400) $PN CE17
J 2
(-5335 4410);
DISPLAY 0.489362 (-5335 4410);
PAINT MONO (-5335 4410);
FORCEPROP 0 LASTPIN (-5325 4300) $PN CL17
J 2
(-5335 4310);
DISPLAY 0.489362 (-5335 4310);
PAINT MONO (-5335 4310);
FORCEPROP 0 LASTPIN (-5325 4200) $PN CU17
J 2
(-5335 4210);
DISPLAY 0.489362 (-5335 4210);
PAINT MONO (-5335 4210);
FORCEPROP 0 LASTPIN (-5325 4100) $PN DC17
J 2
(-5335 4110);
DISPLAY 0.489362 (-5335 4110);
PAINT MONO (-5335 4110);
FORCEPROP 0 LASTPIN (-5325 4000) $PN BW16
J 2
(-5335 4010);
DISPLAY 0.489362 (-5335 4010);
PAINT MONO (-5335 4010);
FORCEPROP 0 LASTPIN (-5325 2250) $PN BL17
J 2
(-5335 2260);
DISPLAY 0.489362 (-5335 2260);
PAINT MONO (-5335 2260);
FORCEPROP 0 LASTPIN (-5325 1200) $PN BF18
J 2
(-5335 1210);
DISPLAY 0.489362 (-5335 1210);
PAINT MONO (-5335 1210);
FORCEPROP 2 LAST PART_TYPE SMLF
J 0
(-5175 6375);
DISPLAY 1.021277 (-5175 6375);
FORCEPROP 1 LAST MATERIAL IO
J 0
(-5170 6182);
DISPLAY 0.489362 (-5170 6182);
PAINT SKYBLUE (-5170 6182);
FORCEPROP 2 LAST VALUE SOCKET6096_13568-001
J 0
(-5175 6275);
DISPLAY 0.489362 (-5175 6275);
PAINT SKYBLUE (-5175 6275);
FORCEPROP 2 LAST CDS_LIB pure_quanta
J 0
(-4525 3625);
DISPLAY INVISIBLE (-4525 3625);
FORCEPROP 1 LAST CDS_LMAN_SYM_OUTLINE -650,2525,650,-2525
J 0
(-4525 3625);
DISPLAY 0.468085 (-4525 3625);
PAINT GREEN (-4525 3625);
DISPLAY INVISIBLE (-4525 3625);
FORCEPROP 1 LAST NEEDS_NO_SIZE TRUE
J 0
(-4525 3625);
DISPLAY 0.723404 (-4525 3625);
PAINT GREEN (-4525 3625);
DISPLAY INVISIBLE (-4525 3625);
FORCEPROP 1 LAST PATH I159
J 0
(-4525 3625);
DISPLAY 0.723404 (-4525 3625);
PAINT GREEN (-4525 3625);
DISPLAY INVISIBLE (-4525 3625);
FORCEPROP 1 LAST PART_NUMBER DGA^6000030
J 0
(-5170 6309);
DISPLAY 0.489362 (-5170 6309);
PAINT SKYBLUE (-5170 6309);
DISPLAY INVISIBLE (-5170 6309);
FORCEADD OFFPAGE..3
(-2525 6025);
FORCEPROP 2 LAST $XR0 95 
J 0
(-2311 6025);
DISPLAY 0.638298 (-2311 6025);
PAINT MONO (-2311 6025);
FORCEPROP 2 LAST CDS_LIB mstr_standard
J 0
(-2525 6025);
DISPLAY 0.723404 (-2525 6025);
PAINT MONO (-2525 6025);
DISPLAY INVISIBLE (-2525 6025);
FORCEPROP 1 LAST OFFPAGE TRUE
J 0
(-2200 5900);
DISPLAY 0.872340 (-2200 5900);
PAINT GREEN (-2200 5900);
DISPLAY INVISIBLE (-2200 5900);
FORCEPROP 1 LAST COMMENT_BODY TRUE
J 0
(-2575 5925);
DISPLAY 0.872340 (-2575 5925);
PAINT GREEN (-2575 5925);
DISPLAY INVISIBLE (-2575 5925);
FORCEPROP 2 LAST PATH I160
J 0
(-2300 6075);
DISPLAY 1.021277 (-2300 6075);
DISPLAY INVISIBLE (-2300 6075);
FORCEADD OFFPAGE..3
(-2525 4225);
FORCEPROP 2 LAST $XR0 95 
J 0
(-2311 4225);
DISPLAY 0.638298 (-2311 4225);
PAINT MONO (-2311 4225);
FORCEPROP 2 LAST CDS_LIB mstr_standard
J 0
(-2525 4225);
DISPLAY 0.723404 (-2525 4225);
PAINT MONO (-2525 4225);
DISPLAY INVISIBLE (-2525 4225);
FORCEPROP 1 LAST OFFPAGE TRUE
J 0
(-2200 4100);
DISPLAY 0.872340 (-2200 4100);
PAINT GREEN (-2200 4100);
DISPLAY INVISIBLE (-2200 4100);
FORCEPROP 1 LAST COMMENT_BODY TRUE
J 0
(-2575 4125);
DISPLAY 0.872340 (-2575 4125);
PAINT GREEN (-2575 4125);
DISPLAY INVISIBLE (-2575 4125);
FORCEPROP 2 LAST PATH I161
J 0
(-2300 4275);
DISPLAY 1.021277 (-2300 4275);
DISPLAY INVISIBLE (-2300 4275);
FORCEADD TAP..1
(-3250 5900);
FORCEPROP 3 LASTPIN (-3300 5900) SIG_NAME M_J_CPU0_SA_DQ<2>
J 0
(-3290 5910);
DISPLAY 0.659574 (-3290 5910);
PAINT MONO (-3290 5910);
DISPLAY INVISIBLE (-3290 5910);
FORCEPROP 1 LASTPIN (-3300 5900) BN 2
J 0
(-3312 5908);
DISPLAY 0.489362 (-3312 5908);
PAINT GREEN (-3312 5908);
FORCEPROP 2 LAST CDS_LIB mstr_standard
J 0
(-3250 5900);
DISPLAY 0.723404 (-3250 5900);
PAINT MONO (-3250 5900);
DISPLAY INVISIBLE (-3250 5900);
FORCEPROP 1 LAST BODY_TYPE PLUMBING
J 0
(-3250 5950);
DISPLAY 0.872340 (-3250 5950);
PAINT GREEN (-3250 5950);
DISPLAY INVISIBLE (-3250 5950);
FORCEPROP 1 LAST HDL_TAP TRUE
J 0
(-2925 5775);
DISPLAY 0.872340 (-2925 5775);
DISPLAY INVISIBLE (-2925 5775);
FORCEPROP 1 LAST PATH I162
J 0
(-3252 5900);
DISPLAY 0.872340 (-3252 5900);
PAINT GREEN (-3252 5900);
DISPLAY INVISIBLE (-3252 5900);
FORCEADD TAP..1
(-3250 6000);
FORCEPROP 3 LASTPIN (-3300 6000) SIG_NAME M_J_CPU0_SA_DQ<0>
J 0
(-3290 6010);
DISPLAY 0.659574 (-3290 6010);
PAINT MONO (-3290 6010);
DISPLAY INVISIBLE (-3290 6010);
FORCEPROP 1 LASTPIN (-3300 6000) BN 0
J 0
(-3312 6008);
DISPLAY 0.489362 (-3312 6008);
PAINT GREEN (-3312 6008);
FORCEPROP 2 LAST CDS_LIB mstr_standard
J 0
(-3250 6000);
DISPLAY 0.723404 (-3250 6000);
PAINT MONO (-3250 6000);
DISPLAY INVISIBLE (-3250 6000);
FORCEPROP 1 LAST BODY_TYPE PLUMBING
J 0
(-3250 6050);
DISPLAY 0.872340 (-3250 6050);
PAINT GREEN (-3250 6050);
DISPLAY INVISIBLE (-3250 6050);
FORCEPROP 1 LAST HDL_TAP TRUE
J 0
(-2925 5875);
DISPLAY 0.872340 (-2925 5875);
DISPLAY INVISIBLE (-2925 5875);
FORCEPROP 1 LAST PATH I163
J 0
(-3252 6000);
DISPLAY 0.872340 (-3252 6000);
PAINT GREEN (-3252 6000);
DISPLAY INVISIBLE (-3252 6000);
FORCEADD TAP..1
(-3250 5950);
FORCEPROP 3 LASTPIN (-3300 5950) SIG_NAME M_J_CPU0_SA_DQ<1>
J 0
(-3290 5960);
DISPLAY 0.659574 (-3290 5960);
PAINT MONO (-3290 5960);
DISPLAY INVISIBLE (-3290 5960);
FORCEPROP 1 LASTPIN (-3300 5950) BN 1
J 0
(-3312 5958);
DISPLAY 0.489362 (-3312 5958);
PAINT GREEN (-3312 5958);
FORCEPROP 2 LAST CDS_LIB mstr_standard
J 0
(-3250 5950);
DISPLAY 0.723404 (-3250 5950);
PAINT MONO (-3250 5950);
DISPLAY INVISIBLE (-3250 5950);
FORCEPROP 1 LAST BODY_TYPE PLUMBING
J 0
(-3250 6000);
DISPLAY 0.872340 (-3250 6000);
PAINT GREEN (-3250 6000);
DISPLAY INVISIBLE (-3250 6000);
FORCEPROP 1 LAST HDL_TAP TRUE
J 0
(-2925 5825);
DISPLAY 0.872340 (-2925 5825);
DISPLAY INVISIBLE (-2925 5825);
FORCEPROP 1 LAST PATH I164
J 0
(-3252 5950);
DISPLAY 0.872340 (-3252 5950);
PAINT GREEN (-3252 5950);
DISPLAY INVISIBLE (-3252 5950);
FORCEADD TAP..1
(-3250 5850);
FORCEPROP 3 LASTPIN (-3300 5850) SIG_NAME M_J_CPU0_SA_DQ<3>
J 0
(-3290 5860);
DISPLAY 0.659574 (-3290 5860);
PAINT MONO (-3290 5860);
DISPLAY INVISIBLE (-3290 5860);
FORCEPROP 1 LASTPIN (-3300 5850) BN 3
J 0
(-3312 5858);
DISPLAY 0.489362 (-3312 5858);
PAINT GREEN (-3312 5858);
FORCEPROP 2 LAST CDS_LIB mstr_standard
J 0
(-3250 5850);
DISPLAY 0.723404 (-3250 5850);
PAINT MONO (-3250 5850);
DISPLAY INVISIBLE (-3250 5850);
FORCEPROP 1 LAST BODY_TYPE PLUMBING
J 0
(-3250 5900);
DISPLAY 0.872340 (-3250 5900);
PAINT GREEN (-3250 5900);
DISPLAY INVISIBLE (-3250 5900);
FORCEPROP 1 LAST HDL_TAP TRUE
J 0
(-2925 5725);
DISPLAY 0.872340 (-2925 5725);
DISPLAY INVISIBLE (-2925 5725);
FORCEPROP 1 LAST PATH I165
J 0
(-3252 5850);
DISPLAY 0.872340 (-3252 5850);
PAINT GREEN (-3252 5850);
DISPLAY INVISIBLE (-3252 5850);
FORCEADD TAP..1
(-3250 5800);
FORCEPROP 3 LASTPIN (-3300 5800) SIG_NAME M_J_CPU0_SA_DQ<4>
J 0
(-3290 5810);
DISPLAY 0.659574 (-3290 5810);
PAINT MONO (-3290 5810);
DISPLAY INVISIBLE (-3290 5810);
FORCEPROP 1 LASTPIN (-3300 5800) BN 4
J 0
(-3312 5808);
DISPLAY 0.489362 (-3312 5808);
PAINT GREEN (-3312 5808);
FORCEPROP 2 LAST CDS_LIB mstr_standard
J 0
(-3250 5800);
DISPLAY 0.723404 (-3250 5800);
PAINT MONO (-3250 5800);
DISPLAY INVISIBLE (-3250 5800);
FORCEPROP 1 LAST BODY_TYPE PLUMBING
J 0
(-3250 5850);
DISPLAY 0.872340 (-3250 5850);
PAINT GREEN (-3250 5850);
DISPLAY INVISIBLE (-3250 5850);
FORCEPROP 1 LAST HDL_TAP TRUE
J 0
(-2925 5675);
DISPLAY 0.872340 (-2925 5675);
DISPLAY INVISIBLE (-2925 5675);
FORCEPROP 1 LAST PATH I166
J 0
(-3252 5800);
DISPLAY 0.872340 (-3252 5800);
PAINT GREEN (-3252 5800);
DISPLAY INVISIBLE (-3252 5800);
FORCEADD TAP..1
(-3250 5700);
FORCEPROP 3 LASTPIN (-3300 5700) SIG_NAME M_J_CPU0_SA_DQ<6>
J 0
(-3290 5710);
DISPLAY 0.659574 (-3290 5710);
PAINT MONO (-3290 5710);
DISPLAY INVISIBLE (-3290 5710);
FORCEPROP 1 LASTPIN (-3300 5700) BN 6
J 0
(-3312 5708);
DISPLAY 0.489362 (-3312 5708);
PAINT GREEN (-3312 5708);
FORCEPROP 2 LAST CDS_LIB mstr_standard
J 0
(-3250 5700);
DISPLAY 0.723404 (-3250 5700);
PAINT MONO (-3250 5700);
DISPLAY INVISIBLE (-3250 5700);
FORCEPROP 1 LAST BODY_TYPE PLUMBING
J 0
(-3250 5750);
DISPLAY 0.872340 (-3250 5750);
PAINT GREEN (-3250 5750);
DISPLAY INVISIBLE (-3250 5750);
FORCEPROP 1 LAST HDL_TAP TRUE
J 0
(-2925 5575);
DISPLAY 0.872340 (-2925 5575);
DISPLAY INVISIBLE (-2925 5575);
FORCEPROP 1 LAST PATH I167
J 0
(-3252 5700);
DISPLAY 0.872340 (-3252 5700);
PAINT GREEN (-3252 5700);
DISPLAY INVISIBLE (-3252 5700);
FORCEADD TAP..1
(-3250 5750);
FORCEPROP 3 LASTPIN (-3300 5750) SIG_NAME M_J_CPU0_SA_DQ<5>
J 0
(-3290 5760);
DISPLAY 0.659574 (-3290 5760);
PAINT MONO (-3290 5760);
DISPLAY INVISIBLE (-3290 5760);
FORCEPROP 1 LASTPIN (-3300 5750) BN 5
J 0
(-3312 5758);
DISPLAY 0.489362 (-3312 5758);
PAINT GREEN (-3312 5758);
FORCEPROP 2 LAST CDS_LIB mstr_standard
J 0
(-3250 5750);
DISPLAY 0.723404 (-3250 5750);
PAINT MONO (-3250 5750);
DISPLAY INVISIBLE (-3250 5750);
FORCEPROP 1 LAST BODY_TYPE PLUMBING
J 0
(-3250 5800);
DISPLAY 0.872340 (-3250 5800);
PAINT GREEN (-3250 5800);
DISPLAY INVISIBLE (-3250 5800);
FORCEPROP 1 LAST HDL_TAP TRUE
J 0
(-2925 5625);
DISPLAY 0.872340 (-2925 5625);
DISPLAY INVISIBLE (-2925 5625);
FORCEPROP 1 LAST PATH I168
J 0
(-3252 5750);
DISPLAY 0.872340 (-3252 5750);
PAINT GREEN (-3252 5750);
DISPLAY INVISIBLE (-3252 5750);
FORCEADD TAP..1
(-3250 5650);
FORCEPROP 3 LASTPIN (-3300 5650) SIG_NAME M_J_CPU0_SA_DQ<7>
J 0
(-3290 5660);
DISPLAY 0.659574 (-3290 5660);
PAINT MONO (-3290 5660);
DISPLAY INVISIBLE (-3290 5660);
FORCEPROP 1 LASTPIN (-3300 5650) BN 7
J 0
(-3312 5658);
DISPLAY 0.489362 (-3312 5658);
PAINT GREEN (-3312 5658);
FORCEPROP 2 LAST CDS_LIB mstr_standard
J 0
(-3250 5650);
DISPLAY 0.723404 (-3250 5650);
PAINT MONO (-3250 5650);
DISPLAY INVISIBLE (-3250 5650);
FORCEPROP 1 LAST BODY_TYPE PLUMBING
J 0
(-3250 5700);
DISPLAY 0.872340 (-3250 5700);
PAINT GREEN (-3250 5700);
DISPLAY INVISIBLE (-3250 5700);
FORCEPROP 1 LAST HDL_TAP TRUE
J 0
(-2925 5525);
DISPLAY 0.872340 (-2925 5525);
DISPLAY INVISIBLE (-2925 5525);
FORCEPROP 1 LAST PATH I169
J 0
(-3252 5650);
DISPLAY 0.872340 (-3252 5650);
PAINT GREEN (-3252 5650);
DISPLAY INVISIBLE (-3252 5650);
FORCEADD TAP..1
(-3250 5550);
FORCEPROP 3 LASTPIN (-3300 5550) SIG_NAME M_J_CPU0_SA_DQ<8>
J 0
(-3290 5560);
DISPLAY 0.659574 (-3290 5560);
PAINT MONO (-3290 5560);
DISPLAY INVISIBLE (-3290 5560);
FORCEPROP 1 LASTPIN (-3300 5550) BN 8
J 0
(-3312 5558);
DISPLAY 0.489362 (-3312 5558);
PAINT GREEN (-3312 5558);
FORCEPROP 2 LAST CDS_LIB mstr_standard
J 0
(-3250 5550);
DISPLAY 0.723404 (-3250 5550);
PAINT MONO (-3250 5550);
DISPLAY INVISIBLE (-3250 5550);
FORCEPROP 1 LAST BODY_TYPE PLUMBING
J 0
(-3250 5600);
DISPLAY 0.872340 (-3250 5600);
PAINT GREEN (-3250 5600);
DISPLAY INVISIBLE (-3250 5600);
FORCEPROP 1 LAST HDL_TAP TRUE
J 0
(-2925 5425);
DISPLAY 0.872340 (-2925 5425);
DISPLAY INVISIBLE (-2925 5425);
FORCEPROP 1 LAST PATH I170
J 0
(-3252 5550);
DISPLAY 0.872340 (-3252 5550);
PAINT GREEN (-3252 5550);
DISPLAY INVISIBLE (-3252 5550);
FORCEADD TAP..1
(-3250 5500);
FORCEPROP 3 LASTPIN (-3300 5500) SIG_NAME M_J_CPU0_SA_DQ<9>
J 0
(-3290 5510);
DISPLAY 0.659574 (-3290 5510);
PAINT MONO (-3290 5510);
DISPLAY INVISIBLE (-3290 5510);
FORCEPROP 1 LASTPIN (-3300 5500) BN 9
J 0
(-3312 5508);
DISPLAY 0.489362 (-3312 5508);
PAINT GREEN (-3312 5508);
FORCEPROP 2 LAST CDS_LIB mstr_standard
J 0
(-3250 5500);
DISPLAY 0.723404 (-3250 5500);
PAINT MONO (-3250 5500);
DISPLAY INVISIBLE (-3250 5500);
FORCEPROP 1 LAST BODY_TYPE PLUMBING
J 0
(-3250 5550);
DISPLAY 0.872340 (-3250 5550);
PAINT GREEN (-3250 5550);
DISPLAY INVISIBLE (-3250 5550);
FORCEPROP 1 LAST HDL_TAP TRUE
J 0
(-2925 5375);
DISPLAY 0.872340 (-2925 5375);
DISPLAY INVISIBLE (-2925 5375);
FORCEPROP 1 LAST PATH I171
J 0
(-3252 5500);
DISPLAY 0.872340 (-3252 5500);
PAINT GREEN (-3252 5500);
DISPLAY INVISIBLE (-3252 5500);
FORCEADD TAP..1
(-3250 5450);
FORCEPROP 3 LASTPIN (-3300 5450) SIG_NAME M_J_CPU0_SA_DQ<10>
J 0
(-3290 5460);
DISPLAY 0.659574 (-3290 5460);
PAINT MONO (-3290 5460);
DISPLAY INVISIBLE (-3290 5460);
FORCEPROP 1 LASTPIN (-3300 5450) BN 10
J 0
(-3312 5458);
DISPLAY 0.489362 (-3312 5458);
PAINT GREEN (-3312 5458);
FORCEPROP 2 LAST CDS_LIB mstr_standard
J 0
(-3250 5450);
DISPLAY 0.723404 (-3250 5450);
PAINT MONO (-3250 5450);
DISPLAY INVISIBLE (-3250 5450);
FORCEPROP 1 LAST BODY_TYPE PLUMBING
J 0
(-3250 5500);
DISPLAY 0.872340 (-3250 5500);
PAINT GREEN (-3250 5500);
DISPLAY INVISIBLE (-3250 5500);
FORCEPROP 1 LAST HDL_TAP TRUE
J 0
(-2925 5325);
DISPLAY 0.872340 (-2925 5325);
DISPLAY INVISIBLE (-2925 5325);
FORCEPROP 1 LAST PATH I172
J 0
(-3252 5450);
DISPLAY 0.872340 (-3252 5450);
PAINT GREEN (-3252 5450);
DISPLAY INVISIBLE (-3252 5450);
FORCEADD TAP..1
(-3250 5400);
FORCEPROP 3 LASTPIN (-3300 5400) SIG_NAME M_J_CPU0_SA_DQ<11>
J 0
(-3290 5410);
DISPLAY 0.659574 (-3290 5410);
PAINT MONO (-3290 5410);
DISPLAY INVISIBLE (-3290 5410);
FORCEPROP 1 LASTPIN (-3300 5400) BN 11
J 0
(-3312 5408);
DISPLAY 0.489362 (-3312 5408);
PAINT GREEN (-3312 5408);
FORCEPROP 2 LAST CDS_LIB mstr_standard
J 0
(-3250 5400);
DISPLAY 0.723404 (-3250 5400);
PAINT MONO (-3250 5400);
DISPLAY INVISIBLE (-3250 5400);
FORCEPROP 1 LAST BODY_TYPE PLUMBING
J 0
(-3250 5450);
DISPLAY 0.872340 (-3250 5450);
PAINT GREEN (-3250 5450);
DISPLAY INVISIBLE (-3250 5450);
FORCEPROP 1 LAST HDL_TAP TRUE
J 0
(-2925 5275);
DISPLAY 0.872340 (-2925 5275);
DISPLAY INVISIBLE (-2925 5275);
FORCEPROP 1 LAST PATH I173
J 0
(-3252 5400);
DISPLAY 0.872340 (-3252 5400);
PAINT GREEN (-3252 5400);
DISPLAY INVISIBLE (-3252 5400);
FORCEADD TAP..1
(-3250 5350);
FORCEPROP 3 LASTPIN (-3300 5350) SIG_NAME M_J_CPU0_SA_DQ<12>
J 0
(-3290 5360);
DISPLAY 0.659574 (-3290 5360);
PAINT MONO (-3290 5360);
DISPLAY INVISIBLE (-3290 5360);
FORCEPROP 1 LASTPIN (-3300 5350) BN 12
J 0
(-3312 5358);
DISPLAY 0.489362 (-3312 5358);
PAINT GREEN (-3312 5358);
FORCEPROP 2 LAST CDS_LIB mstr_standard
J 0
(-3250 5350);
DISPLAY 0.723404 (-3250 5350);
PAINT MONO (-3250 5350);
DISPLAY INVISIBLE (-3250 5350);
FORCEPROP 1 LAST BODY_TYPE PLUMBING
J 0
(-3250 5400);
DISPLAY 0.872340 (-3250 5400);
PAINT GREEN (-3250 5400);
DISPLAY INVISIBLE (-3250 5400);
FORCEPROP 1 LAST HDL_TAP TRUE
J 0
(-2925 5225);
DISPLAY 0.872340 (-2925 5225);
DISPLAY INVISIBLE (-2925 5225);
FORCEPROP 1 LAST PATH I174
J 0
(-3252 5350);
DISPLAY 0.872340 (-3252 5350);
PAINT GREEN (-3252 5350);
DISPLAY INVISIBLE (-3252 5350);
FORCEADD TAP..1
(-3250 5300);
FORCEPROP 3 LASTPIN (-3300 5300) SIG_NAME M_J_CPU0_SA_DQ<13>
J 0
(-3290 5310);
DISPLAY 0.659574 (-3290 5310);
PAINT MONO (-3290 5310);
DISPLAY INVISIBLE (-3290 5310);
FORCEPROP 1 LASTPIN (-3300 5300) BN 13
J 0
(-3312 5308);
DISPLAY 0.489362 (-3312 5308);
PAINT GREEN (-3312 5308);
FORCEPROP 2 LAST CDS_LIB mstr_standard
J 0
(-3250 5300);
DISPLAY 0.723404 (-3250 5300);
PAINT MONO (-3250 5300);
DISPLAY INVISIBLE (-3250 5300);
FORCEPROP 1 LAST BODY_TYPE PLUMBING
J 0
(-3250 5350);
DISPLAY 0.872340 (-3250 5350);
PAINT GREEN (-3250 5350);
DISPLAY INVISIBLE (-3250 5350);
FORCEPROP 1 LAST HDL_TAP TRUE
J 0
(-2925 5175);
DISPLAY 0.872340 (-2925 5175);
DISPLAY INVISIBLE (-2925 5175);
FORCEPROP 1 LAST PATH I175
J 0
(-3252 5300);
DISPLAY 0.872340 (-3252 5300);
PAINT GREEN (-3252 5300);
DISPLAY INVISIBLE (-3252 5300);
FORCEADD TAP..1
(-3250 5250);
FORCEPROP 3 LASTPIN (-3300 5250) SIG_NAME M_J_CPU0_SA_DQ<14>
J 0
(-3290 5260);
DISPLAY 0.659574 (-3290 5260);
PAINT MONO (-3290 5260);
DISPLAY INVISIBLE (-3290 5260);
FORCEPROP 1 LASTPIN (-3300 5250) BN 14
J 0
(-3312 5258);
DISPLAY 0.489362 (-3312 5258);
PAINT GREEN (-3312 5258);
FORCEPROP 2 LAST CDS_LIB mstr_standard
J 0
(-3250 5250);
DISPLAY 0.723404 (-3250 5250);
PAINT MONO (-3250 5250);
DISPLAY INVISIBLE (-3250 5250);
FORCEPROP 1 LAST BODY_TYPE PLUMBING
J 0
(-3250 5300);
DISPLAY 0.872340 (-3250 5300);
PAINT GREEN (-3250 5300);
DISPLAY INVISIBLE (-3250 5300);
FORCEPROP 1 LAST HDL_TAP TRUE
J 0
(-2925 5125);
DISPLAY 0.872340 (-2925 5125);
DISPLAY INVISIBLE (-2925 5125);
FORCEPROP 1 LAST PATH I176
J 0
(-3252 5250);
DISPLAY 0.872340 (-3252 5250);
PAINT GREEN (-3252 5250);
DISPLAY INVISIBLE (-3252 5250);
FORCEADD TAP..1
(-3250 5200);
FORCEPROP 3 LASTPIN (-3300 5200) SIG_NAME M_J_CPU0_SA_DQ<15>
J 0
(-3290 5210);
DISPLAY 0.659574 (-3290 5210);
PAINT MONO (-3290 5210);
DISPLAY INVISIBLE (-3290 5210);
FORCEPROP 1 LASTPIN (-3300 5200) BN 15
J 0
(-3312 5208);
DISPLAY 0.489362 (-3312 5208);
PAINT GREEN (-3312 5208);
FORCEPROP 2 LAST CDS_LIB mstr_standard
J 0
(-3250 5200);
DISPLAY 0.723404 (-3250 5200);
PAINT MONO (-3250 5200);
DISPLAY INVISIBLE (-3250 5200);
FORCEPROP 1 LAST BODY_TYPE PLUMBING
J 0
(-3250 5250);
DISPLAY 0.872340 (-3250 5250);
PAINT GREEN (-3250 5250);
DISPLAY INVISIBLE (-3250 5250);
FORCEPROP 1 LAST HDL_TAP TRUE
J 0
(-2925 5075);
DISPLAY 0.872340 (-2925 5075);
DISPLAY INVISIBLE (-2925 5075);
FORCEPROP 1 LAST PATH I177
J 0
(-3252 5200);
DISPLAY 0.872340 (-3252 5200);
PAINT GREEN (-3252 5200);
DISPLAY INVISIBLE (-3252 5200);
FORCEADD TAP..1
(-3250 5000);
FORCEPROP 3 LASTPIN (-3300 5000) SIG_NAME M_J_CPU0_SA_DQ<18>
J 0
(-3290 5010);
DISPLAY 0.659574 (-3290 5010);
PAINT MONO (-3290 5010);
DISPLAY INVISIBLE (-3290 5010);
FORCEPROP 1 LASTPIN (-3300 5000) BN 18
J 0
(-3312 5008);
DISPLAY 0.489362 (-3312 5008);
PAINT GREEN (-3312 5008);
FORCEPROP 2 LAST CDS_LIB mstr_standard
J 0
(-3250 5000);
DISPLAY 0.723404 (-3250 5000);
PAINT MONO (-3250 5000);
DISPLAY INVISIBLE (-3250 5000);
FORCEPROP 1 LAST BODY_TYPE PLUMBING
J 0
(-3250 5050);
DISPLAY 0.872340 (-3250 5050);
PAINT GREEN (-3250 5050);
DISPLAY INVISIBLE (-3250 5050);
FORCEPROP 1 LAST HDL_TAP TRUE
J 0
(-2925 4875);
DISPLAY 0.872340 (-2925 4875);
DISPLAY INVISIBLE (-2925 4875);
FORCEPROP 1 LAST PATH I178
J 0
(-3252 5000);
DISPLAY 0.872340 (-3252 5000);
PAINT GREEN (-3252 5000);
DISPLAY INVISIBLE (-3252 5000);
FORCEADD TAP..1
(-3250 5100);
FORCEPROP 3 LASTPIN (-3300 5100) SIG_NAME M_J_CPU0_SA_DQ<16>
J 0
(-3290 5110);
DISPLAY 0.659574 (-3290 5110);
PAINT MONO (-3290 5110);
DISPLAY INVISIBLE (-3290 5110);
FORCEPROP 1 LASTPIN (-3300 5100) BN 16
J 0
(-3312 5108);
DISPLAY 0.489362 (-3312 5108);
PAINT GREEN (-3312 5108);
FORCEPROP 2 LAST CDS_LIB mstr_standard
J 0
(-3250 5100);
DISPLAY 0.723404 (-3250 5100);
PAINT MONO (-3250 5100);
DISPLAY INVISIBLE (-3250 5100);
FORCEPROP 1 LAST BODY_TYPE PLUMBING
J 0
(-3250 5150);
DISPLAY 0.872340 (-3250 5150);
PAINT GREEN (-3250 5150);
DISPLAY INVISIBLE (-3250 5150);
FORCEPROP 1 LAST HDL_TAP TRUE
J 0
(-2925 4975);
DISPLAY 0.872340 (-2925 4975);
DISPLAY INVISIBLE (-2925 4975);
FORCEPROP 1 LAST PATH I179
J 0
(-3252 5100);
DISPLAY 0.872340 (-3252 5100);
PAINT GREEN (-3252 5100);
DISPLAY INVISIBLE (-3252 5100);
FORCEADD TAP..1
(-3250 5050);
FORCEPROP 3 LASTPIN (-3300 5050) SIG_NAME M_J_CPU0_SA_DQ<17>
J 0
(-3290 5060);
DISPLAY 0.659574 (-3290 5060);
PAINT MONO (-3290 5060);
DISPLAY INVISIBLE (-3290 5060);
FORCEPROP 1 LASTPIN (-3300 5050) BN 17
J 0
(-3312 5058);
DISPLAY 0.489362 (-3312 5058);
PAINT GREEN (-3312 5058);
FORCEPROP 2 LAST CDS_LIB mstr_standard
J 0
(-3250 5050);
DISPLAY 0.723404 (-3250 5050);
PAINT MONO (-3250 5050);
DISPLAY INVISIBLE (-3250 5050);
FORCEPROP 1 LAST BODY_TYPE PLUMBING
J 0
(-3250 5100);
DISPLAY 0.872340 (-3250 5100);
PAINT GREEN (-3250 5100);
DISPLAY INVISIBLE (-3250 5100);
FORCEPROP 1 LAST HDL_TAP TRUE
J 0
(-2925 4925);
DISPLAY 0.872340 (-2925 4925);
DISPLAY INVISIBLE (-2925 4925);
FORCEPROP 1 LAST PATH I180
J 0
(-3252 5050);
DISPLAY 0.872340 (-3252 5050);
PAINT GREEN (-3252 5050);
DISPLAY INVISIBLE (-3252 5050);
FORCEADD TAP..1
(-3250 4950);
FORCEPROP 3 LASTPIN (-3300 4950) SIG_NAME M_J_CPU0_SA_DQ<19>
J 0
(-3290 4960);
DISPLAY 0.659574 (-3290 4960);
PAINT MONO (-3290 4960);
DISPLAY INVISIBLE (-3290 4960);
FORCEPROP 1 LASTPIN (-3300 4950) BN 19
J 0
(-3312 4958);
DISPLAY 0.489362 (-3312 4958);
PAINT GREEN (-3312 4958);
FORCEPROP 2 LAST CDS_LIB mstr_standard
J 0
(-3250 4950);
DISPLAY 0.723404 (-3250 4950);
PAINT MONO (-3250 4950);
DISPLAY INVISIBLE (-3250 4950);
FORCEPROP 1 LAST BODY_TYPE PLUMBING
J 0
(-3250 5000);
DISPLAY 0.872340 (-3250 5000);
PAINT GREEN (-3250 5000);
DISPLAY INVISIBLE (-3250 5000);
FORCEPROP 1 LAST HDL_TAP TRUE
J 0
(-2925 4825);
DISPLAY 0.872340 (-2925 4825);
DISPLAY INVISIBLE (-2925 4825);
FORCEPROP 1 LAST PATH I181
J 0
(-3252 4950);
DISPLAY 0.872340 (-3252 4950);
PAINT GREEN (-3252 4950);
DISPLAY INVISIBLE (-3252 4950);
FORCEADD TAP..1
(-3250 4900);
FORCEPROP 3 LASTPIN (-3300 4900) SIG_NAME M_J_CPU0_SA_DQ<20>
J 0
(-3290 4910);
DISPLAY 0.659574 (-3290 4910);
PAINT MONO (-3290 4910);
DISPLAY INVISIBLE (-3290 4910);
FORCEPROP 1 LASTPIN (-3300 4900) BN 20
J 0
(-3312 4908);
DISPLAY 0.489362 (-3312 4908);
PAINT GREEN (-3312 4908);
FORCEPROP 2 LAST CDS_LIB mstr_standard
J 0
(-3250 4900);
DISPLAY 0.723404 (-3250 4900);
PAINT MONO (-3250 4900);
DISPLAY INVISIBLE (-3250 4900);
FORCEPROP 1 LAST BODY_TYPE PLUMBING
J 0
(-3250 4950);
DISPLAY 0.872340 (-3250 4950);
PAINT GREEN (-3250 4950);
DISPLAY INVISIBLE (-3250 4950);
FORCEPROP 1 LAST HDL_TAP TRUE
J 0
(-2925 4775);
DISPLAY 0.872340 (-2925 4775);
DISPLAY INVISIBLE (-2925 4775);
FORCEPROP 1 LAST PATH I182
J 0
(-3252 4900);
DISPLAY 0.872340 (-3252 4900);
PAINT GREEN (-3252 4900);
DISPLAY INVISIBLE (-3252 4900);
FORCEADD TAP..1
(-3250 4800);
FORCEPROP 3 LASTPIN (-3300 4800) SIG_NAME M_J_CPU0_SA_DQ<22>
J 0
(-3290 4810);
DISPLAY 0.659574 (-3290 4810);
PAINT MONO (-3290 4810);
DISPLAY INVISIBLE (-3290 4810);
FORCEPROP 1 LASTPIN (-3300 4800) BN 22
J 0
(-3312 4808);
DISPLAY 0.489362 (-3312 4808);
PAINT GREEN (-3312 4808);
FORCEPROP 2 LAST CDS_LIB mstr_standard
J 0
(-3250 4800);
DISPLAY 0.723404 (-3250 4800);
PAINT MONO (-3250 4800);
DISPLAY INVISIBLE (-3250 4800);
FORCEPROP 1 LAST BODY_TYPE PLUMBING
J 0
(-3250 4850);
DISPLAY 0.872340 (-3250 4850);
PAINT GREEN (-3250 4850);
DISPLAY INVISIBLE (-3250 4850);
FORCEPROP 1 LAST HDL_TAP TRUE
J 0
(-2925 4675);
DISPLAY 0.872340 (-2925 4675);
DISPLAY INVISIBLE (-2925 4675);
FORCEPROP 1 LAST PATH I183
J 0
(-3252 4800);
DISPLAY 0.872340 (-3252 4800);
PAINT GREEN (-3252 4800);
DISPLAY INVISIBLE (-3252 4800);
FORCEADD TAP..1
(-3250 4850);
FORCEPROP 3 LASTPIN (-3300 4850) SIG_NAME M_J_CPU0_SA_DQ<21>
J 0
(-3290 4860);
DISPLAY 0.659574 (-3290 4860);
PAINT MONO (-3290 4860);
DISPLAY INVISIBLE (-3290 4860);
FORCEPROP 1 LASTPIN (-3300 4850) BN 21
J 0
(-3312 4858);
DISPLAY 0.489362 (-3312 4858);
PAINT GREEN (-3312 4858);
FORCEPROP 2 LAST CDS_LIB mstr_standard
J 0
(-3250 4850);
DISPLAY 0.723404 (-3250 4850);
PAINT MONO (-3250 4850);
DISPLAY INVISIBLE (-3250 4850);
FORCEPROP 1 LAST BODY_TYPE PLUMBING
J 0
(-3250 4900);
DISPLAY 0.872340 (-3250 4900);
PAINT GREEN (-3250 4900);
DISPLAY INVISIBLE (-3250 4900);
FORCEPROP 1 LAST HDL_TAP TRUE
J 0
(-2925 4725);
DISPLAY 0.872340 (-2925 4725);
DISPLAY INVISIBLE (-2925 4725);
FORCEPROP 1 LAST PATH I184
J 0
(-3252 4850);
DISPLAY 0.872340 (-3252 4850);
PAINT GREEN (-3252 4850);
DISPLAY INVISIBLE (-3252 4850);
FORCEADD TAP..1
(-3250 4750);
FORCEPROP 3 LASTPIN (-3300 4750) SIG_NAME M_J_CPU0_SA_DQ<23>
J 0
(-3290 4760);
DISPLAY 0.659574 (-3290 4760);
PAINT MONO (-3290 4760);
DISPLAY INVISIBLE (-3290 4760);
FORCEPROP 1 LASTPIN (-3300 4750) BN 23
J 0
(-3312 4758);
DISPLAY 0.489362 (-3312 4758);
PAINT GREEN (-3312 4758);
FORCEPROP 2 LAST CDS_LIB mstr_standard
J 0
(-3250 4750);
DISPLAY 0.723404 (-3250 4750);
PAINT MONO (-3250 4750);
DISPLAY INVISIBLE (-3250 4750);
FORCEPROP 1 LAST BODY_TYPE PLUMBING
J 0
(-3250 4800);
DISPLAY 0.872340 (-3250 4800);
PAINT GREEN (-3250 4800);
DISPLAY INVISIBLE (-3250 4800);
FORCEPROP 1 LAST HDL_TAP TRUE
J 0
(-2925 4625);
DISPLAY 0.872340 (-2925 4625);
DISPLAY INVISIBLE (-2925 4625);
FORCEPROP 1 LAST PATH I185
J 0
(-3252 4750);
DISPLAY 0.872340 (-3252 4750);
PAINT GREEN (-3252 4750);
DISPLAY INVISIBLE (-3252 4750);
FORCEADD TAP..1
(-3250 4650);
FORCEPROP 3 LASTPIN (-3300 4650) SIG_NAME M_J_CPU0_SA_DQ<24>
J 0
(-3290 4660);
DISPLAY 0.659574 (-3290 4660);
PAINT MONO (-3290 4660);
DISPLAY INVISIBLE (-3290 4660);
FORCEPROP 1 LASTPIN (-3300 4650) BN 24
J 0
(-3312 4658);
DISPLAY 0.489362 (-3312 4658);
PAINT GREEN (-3312 4658);
FORCEPROP 2 LAST CDS_LIB mstr_standard
J 0
(-3250 4650);
DISPLAY 0.723404 (-3250 4650);
PAINT MONO (-3250 4650);
DISPLAY INVISIBLE (-3250 4650);
FORCEPROP 1 LAST BODY_TYPE PLUMBING
J 0
(-3250 4700);
DISPLAY 0.872340 (-3250 4700);
PAINT GREEN (-3250 4700);
DISPLAY INVISIBLE (-3250 4700);
FORCEPROP 1 LAST HDL_TAP TRUE
J 0
(-2925 4525);
DISPLAY 0.872340 (-2925 4525);
DISPLAY INVISIBLE (-2925 4525);
FORCEPROP 1 LAST PATH I186
J 0
(-3252 4650);
DISPLAY 0.872340 (-3252 4650);
PAINT GREEN (-3252 4650);
DISPLAY INVISIBLE (-3252 4650);
FORCEADD TAP..1
(-3250 4500);
FORCEPROP 3 LASTPIN (-3300 4500) SIG_NAME M_J_CPU0_SA_DQ<27>
J 0
(-3290 4510);
DISPLAY 0.659574 (-3290 4510);
PAINT MONO (-3290 4510);
DISPLAY INVISIBLE (-3290 4510);
FORCEPROP 1 LASTPIN (-3300 4500) BN 27
J 0
(-3312 4508);
DISPLAY 0.489362 (-3312 4508);
PAINT GREEN (-3312 4508);
FORCEPROP 2 LAST CDS_LIB mstr_standard
J 0
(-3250 4500);
DISPLAY 0.723404 (-3250 4500);
PAINT MONO (-3250 4500);
DISPLAY INVISIBLE (-3250 4500);
FORCEPROP 1 LAST BODY_TYPE PLUMBING
J 0
(-3250 4550);
DISPLAY 0.872340 (-3250 4550);
PAINT GREEN (-3250 4550);
DISPLAY INVISIBLE (-3250 4550);
FORCEPROP 1 LAST HDL_TAP TRUE
J 0
(-2925 4375);
DISPLAY 0.872340 (-2925 4375);
DISPLAY INVISIBLE (-2925 4375);
FORCEPROP 1 LAST PATH I187
J 0
(-3252 4500);
DISPLAY 0.872340 (-3252 4500);
PAINT GREEN (-3252 4500);
DISPLAY INVISIBLE (-3252 4500);
FORCEADD TAP..1
(-3250 4550);
FORCEPROP 3 LASTPIN (-3300 4550) SIG_NAME M_J_CPU0_SA_DQ<26>
J 0
(-3290 4560);
DISPLAY 0.659574 (-3290 4560);
PAINT MONO (-3290 4560);
DISPLAY INVISIBLE (-3290 4560);
FORCEPROP 1 LASTPIN (-3300 4550) BN 26
J 0
(-3312 4558);
DISPLAY 0.489362 (-3312 4558);
PAINT GREEN (-3312 4558);
FORCEPROP 2 LAST CDS_LIB mstr_standard
J 0
(-3250 4550);
DISPLAY 0.723404 (-3250 4550);
PAINT MONO (-3250 4550);
DISPLAY INVISIBLE (-3250 4550);
FORCEPROP 1 LAST BODY_TYPE PLUMBING
J 0
(-3250 4600);
DISPLAY 0.872340 (-3250 4600);
PAINT GREEN (-3250 4600);
DISPLAY INVISIBLE (-3250 4600);
FORCEPROP 1 LAST HDL_TAP TRUE
J 0
(-2925 4425);
DISPLAY 0.872340 (-2925 4425);
DISPLAY INVISIBLE (-2925 4425);
FORCEPROP 1 LAST PATH I188
J 0
(-3252 4550);
DISPLAY 0.872340 (-3252 4550);
PAINT GREEN (-3252 4550);
DISPLAY INVISIBLE (-3252 4550);
FORCEADD TAP..1
(-3250 4600);
FORCEPROP 3 LASTPIN (-3300 4600) SIG_NAME M_J_CPU0_SA_DQ<25>
J 0
(-3290 4610);
DISPLAY 0.659574 (-3290 4610);
PAINT MONO (-3290 4610);
DISPLAY INVISIBLE (-3290 4610);
FORCEPROP 1 LASTPIN (-3300 4600) BN 25
J 0
(-3312 4608);
DISPLAY 0.489362 (-3312 4608);
PAINT GREEN (-3312 4608);
FORCEPROP 2 LAST CDS_LIB mstr_standard
J 0
(-3250 4600);
DISPLAY 0.723404 (-3250 4600);
PAINT MONO (-3250 4600);
DISPLAY INVISIBLE (-3250 4600);
FORCEPROP 1 LAST BODY_TYPE PLUMBING
J 0
(-3250 4650);
DISPLAY 0.872340 (-3250 4650);
PAINT GREEN (-3250 4650);
DISPLAY INVISIBLE (-3250 4650);
FORCEPROP 1 LAST HDL_TAP TRUE
J 0
(-2925 4475);
DISPLAY 0.872340 (-2925 4475);
DISPLAY INVISIBLE (-2925 4475);
FORCEPROP 1 LAST PATH I189
J 0
(-3252 4600);
DISPLAY 0.872340 (-3252 4600);
PAINT GREEN (-3252 4600);
DISPLAY INVISIBLE (-3252 4600);
FORCEADD TAP..1
(-3250 4450);
FORCEPROP 3 LASTPIN (-3300 4450) SIG_NAME M_J_CPU0_SA_DQ<28>
J 0
(-3290 4460);
DISPLAY 0.659574 (-3290 4460);
PAINT MONO (-3290 4460);
DISPLAY INVISIBLE (-3290 4460);
FORCEPROP 1 LASTPIN (-3300 4450) BN 28
J 0
(-3312 4458);
DISPLAY 0.489362 (-3312 4458);
PAINT GREEN (-3312 4458);
FORCEPROP 2 LAST CDS_LIB mstr_standard
J 0
(-3250 4450);
DISPLAY 0.723404 (-3250 4450);
PAINT MONO (-3250 4450);
DISPLAY INVISIBLE (-3250 4450);
FORCEPROP 1 LAST BODY_TYPE PLUMBING
J 0
(-3250 4500);
DISPLAY 0.872340 (-3250 4500);
PAINT GREEN (-3250 4500);
DISPLAY INVISIBLE (-3250 4500);
FORCEPROP 1 LAST HDL_TAP TRUE
J 0
(-2925 4325);
DISPLAY 0.872340 (-2925 4325);
DISPLAY INVISIBLE (-2925 4325);
FORCEPROP 1 LAST PATH I190
J 0
(-3252 4450);
DISPLAY 0.872340 (-3252 4450);
PAINT GREEN (-3252 4450);
DISPLAY INVISIBLE (-3252 4450);
FORCEADD TAP..1
(-3250 4400);
FORCEPROP 3 LASTPIN (-3300 4400) SIG_NAME M_J_CPU0_SA_DQ<29>
J 0
(-3290 4410);
DISPLAY 0.659574 (-3290 4410);
PAINT MONO (-3290 4410);
DISPLAY INVISIBLE (-3290 4410);
FORCEPROP 1 LASTPIN (-3300 4400) BN 29
J 0
(-3312 4408);
DISPLAY 0.489362 (-3312 4408);
PAINT GREEN (-3312 4408);
FORCEPROP 2 LAST CDS_LIB mstr_standard
J 0
(-3250 4400);
DISPLAY 0.723404 (-3250 4400);
PAINT MONO (-3250 4400);
DISPLAY INVISIBLE (-3250 4400);
FORCEPROP 1 LAST BODY_TYPE PLUMBING
J 0
(-3250 4450);
DISPLAY 0.872340 (-3250 4450);
PAINT GREEN (-3250 4450);
DISPLAY INVISIBLE (-3250 4450);
FORCEPROP 1 LAST HDL_TAP TRUE
J 0
(-2925 4275);
DISPLAY 0.872340 (-2925 4275);
DISPLAY INVISIBLE (-2925 4275);
FORCEPROP 1 LAST PATH I191
J 0
(-3252 4400);
DISPLAY 0.872340 (-3252 4400);
PAINT GREEN (-3252 4400);
DISPLAY INVISIBLE (-3252 4400);
FORCEADD TAP..1
(-3250 4300);
FORCEPROP 3 LASTPIN (-3300 4300) SIG_NAME M_J_CPU0_SA_DQ<31>
J 0
(-3290 4310);
DISPLAY 0.659574 (-3290 4310);
PAINT MONO (-3290 4310);
DISPLAY INVISIBLE (-3290 4310);
FORCEPROP 1 LASTPIN (-3300 4300) BN 31
J 0
(-3312 4308);
DISPLAY 0.489362 (-3312 4308);
PAINT GREEN (-3312 4308);
FORCEPROP 2 LAST CDS_LIB mstr_standard
J 0
(-3250 4300);
DISPLAY 0.723404 (-3250 4300);
PAINT MONO (-3250 4300);
DISPLAY INVISIBLE (-3250 4300);
FORCEPROP 1 LAST BODY_TYPE PLUMBING
J 0
(-3250 4350);
DISPLAY 0.872340 (-3250 4350);
PAINT GREEN (-3250 4350);
DISPLAY INVISIBLE (-3250 4350);
FORCEPROP 1 LAST HDL_TAP TRUE
J 0
(-2925 4175);
DISPLAY 0.872340 (-2925 4175);
DISPLAY INVISIBLE (-2925 4175);
FORCEPROP 1 LAST PATH I192
J 0
(-3252 4300);
DISPLAY 0.872340 (-3252 4300);
PAINT GREEN (-3252 4300);
DISPLAY INVISIBLE (-3252 4300);
FORCEADD TAP..1
(-3250 4350);
FORCEPROP 3 LASTPIN (-3300 4350) SIG_NAME M_J_CPU0_SA_DQ<30>
J 0
(-3290 4360);
DISPLAY 0.659574 (-3290 4360);
PAINT MONO (-3290 4360);
DISPLAY INVISIBLE (-3290 4360);
FORCEPROP 1 LASTPIN (-3300 4350) BN 30
J 0
(-3312 4358);
DISPLAY 0.489362 (-3312 4358);
PAINT GREEN (-3312 4358);
FORCEPROP 2 LAST CDS_LIB mstr_standard
J 0
(-3250 4350);
DISPLAY 0.723404 (-3250 4350);
PAINT MONO (-3250 4350);
DISPLAY INVISIBLE (-3250 4350);
FORCEPROP 1 LAST BODY_TYPE PLUMBING
J 0
(-3250 4400);
DISPLAY 0.872340 (-3250 4400);
PAINT GREEN (-3250 4400);
DISPLAY INVISIBLE (-3250 4400);
FORCEPROP 1 LAST HDL_TAP TRUE
J 0
(-2925 4225);
DISPLAY 0.872340 (-2925 4225);
DISPLAY INVISIBLE (-2925 4225);
FORCEPROP 1 LAST PATH I193
J 0
(-3252 4350);
DISPLAY 0.872340 (-3252 4350);
PAINT GREEN (-3252 4350);
DISPLAY INVISIBLE (-3252 4350);
FORCEADD TAP..1
(-3250 4200);
FORCEPROP 3 LASTPIN (-3300 4200) SIG_NAME M_J_CPU0_SB_DQ<0>
J 0
(-3290 4210);
DISPLAY 0.659574 (-3290 4210);
PAINT MONO (-3290 4210);
DISPLAY INVISIBLE (-3290 4210);
FORCEPROP 1 LASTPIN (-3300 4200) BN 0
J 0
(-3312 4208);
DISPLAY 0.489362 (-3312 4208);
PAINT GREEN (-3312 4208);
FORCEPROP 2 LAST CDS_LIB mstr_standard
J 0
(-3250 4200);
DISPLAY 0.723404 (-3250 4200);
PAINT MONO (-3250 4200);
DISPLAY INVISIBLE (-3250 4200);
FORCEPROP 1 LAST BODY_TYPE PLUMBING
J 0
(-3250 4250);
DISPLAY 0.872340 (-3250 4250);
PAINT GREEN (-3250 4250);
DISPLAY INVISIBLE (-3250 4250);
FORCEPROP 1 LAST HDL_TAP TRUE
J 0
(-2925 4075);
DISPLAY 0.872340 (-2925 4075);
DISPLAY INVISIBLE (-2925 4075);
FORCEPROP 1 LAST PATH I194
J 0
(-3252 4200);
DISPLAY 0.872340 (-3252 4200);
PAINT GREEN (-3252 4200);
DISPLAY INVISIBLE (-3252 4200);
FORCEADD TAP..1
(-3250 4150);
FORCEPROP 3 LASTPIN (-3300 4150) SIG_NAME M_J_CPU0_SB_DQ<1>
J 0
(-3290 4160);
DISPLAY 0.659574 (-3290 4160);
PAINT MONO (-3290 4160);
DISPLAY INVISIBLE (-3290 4160);
FORCEPROP 1 LASTPIN (-3300 4150) BN 1
J 0
(-3312 4158);
DISPLAY 0.489362 (-3312 4158);
PAINT GREEN (-3312 4158);
FORCEPROP 2 LAST CDS_LIB mstr_standard
J 0
(-3250 4150);
DISPLAY 0.723404 (-3250 4150);
PAINT MONO (-3250 4150);
DISPLAY INVISIBLE (-3250 4150);
FORCEPROP 1 LAST BODY_TYPE PLUMBING
J 0
(-3250 4200);
DISPLAY 0.872340 (-3250 4200);
PAINT GREEN (-3250 4200);
DISPLAY INVISIBLE (-3250 4200);
FORCEPROP 1 LAST HDL_TAP TRUE
J 0
(-2925 4025);
DISPLAY 0.872340 (-2925 4025);
DISPLAY INVISIBLE (-2925 4025);
FORCEPROP 1 LAST PATH I195
J 0
(-3252 4150);
DISPLAY 0.872340 (-3252 4150);
PAINT GREEN (-3252 4150);
DISPLAY INVISIBLE (-3252 4150);
FORCEADD TAP..1
(-3250 4100);
FORCEPROP 3 LASTPIN (-3300 4100) SIG_NAME M_J_CPU0_SB_DQ<2>
J 0
(-3290 4110);
DISPLAY 0.659574 (-3290 4110);
PAINT MONO (-3290 4110);
DISPLAY INVISIBLE (-3290 4110);
FORCEPROP 1 LASTPIN (-3300 4100) BN 2
J 0
(-3312 4108);
DISPLAY 0.489362 (-3312 4108);
PAINT GREEN (-3312 4108);
FORCEPROP 2 LAST CDS_LIB mstr_standard
J 0
(-3250 4100);
DISPLAY 0.723404 (-3250 4100);
PAINT MONO (-3250 4100);
DISPLAY INVISIBLE (-3250 4100);
FORCEPROP 1 LAST BODY_TYPE PLUMBING
J 0
(-3250 4150);
DISPLAY 0.872340 (-3250 4150);
PAINT GREEN (-3250 4150);
DISPLAY INVISIBLE (-3250 4150);
FORCEPROP 1 LAST HDL_TAP TRUE
J 0
(-2925 3975);
DISPLAY 0.872340 (-2925 3975);
DISPLAY INVISIBLE (-2925 3975);
FORCEPROP 1 LAST PATH I196
J 0
(-3252 4100);
DISPLAY 0.872340 (-3252 4100);
PAINT GREEN (-3252 4100);
DISPLAY INVISIBLE (-3252 4100);
FORCEADD OFFPAGE..6
R 2
(-2650 2450);
FORCEPROP 2 LAST $XR0 95 
J 0
(-2436 2450);
DISPLAY 0.638298 (-2436 2450);
PAINT MONO (-2436 2450);
FORCEPROP 2 LAST CDS_LIB mstr_standard
J 2
(-2650 2450);
DISPLAY 0.723404 (-2650 2450);
PAINT MONO (-2650 2450);
DISPLAY INVISIBLE (-2650 2450);
FORCEPROP 1 LAST OFFPAGE TRUE
J 2
(-2975 2325);
DISPLAY 0.872340 (-2975 2325);
PAINT GREEN (-2975 2325);
DISPLAY INVISIBLE (-2975 2325);
FORCEPROP 1 LAST COMMENT_BODY TRUE
J 2
(-2750 2375);
DISPLAY 0.872340 (-2750 2375);
PAINT GREEN (-2750 2375);
DISPLAY INVISIBLE (-2750 2375);
FORCEPROP 2 LAST PATH I197
J 0
(-2425 2500);
DISPLAY 1.021277 (-2425 2500);
DISPLAY INVISIBLE (-2425 2500);
FORCEADD TAP..1
(-3250 4050);
FORCEPROP 3 LASTPIN (-3300 4050) SIG_NAME M_J_CPU0_SB_DQ<3>
J 0
(-3290 4060);
DISPLAY 0.659574 (-3290 4060);
PAINT MONO (-3290 4060);
DISPLAY INVISIBLE (-3290 4060);
FORCEPROP 1 LASTPIN (-3300 4050) BN 3
J 0
(-3312 4058);
DISPLAY 0.489362 (-3312 4058);
PAINT GREEN (-3312 4058);
FORCEPROP 2 LAST CDS_LIB mstr_standard
J 0
(-3250 4050);
DISPLAY 0.723404 (-3250 4050);
PAINT MONO (-3250 4050);
DISPLAY INVISIBLE (-3250 4050);
FORCEPROP 1 LAST BODY_TYPE PLUMBING
J 0
(-3250 4100);
DISPLAY 0.872340 (-3250 4100);
PAINT GREEN (-3250 4100);
DISPLAY INVISIBLE (-3250 4100);
FORCEPROP 1 LAST HDL_TAP TRUE
J 0
(-2925 3925);
DISPLAY 0.872340 (-2925 3925);
DISPLAY INVISIBLE (-2925 3925);
FORCEPROP 1 LAST PATH I198
J 0
(-3252 4050);
DISPLAY 0.872340 (-3252 4050);
PAINT GREEN (-3252 4050);
DISPLAY INVISIBLE (-3252 4050);
FORCEADD TAP..1
(-3250 4000);
FORCEPROP 3 LASTPIN (-3300 4000) SIG_NAME M_J_CPU0_SB_DQ<4>
J 0
(-3290 4010);
DISPLAY 0.659574 (-3290 4010);
PAINT MONO (-3290 4010);
DISPLAY INVISIBLE (-3290 4010);
FORCEPROP 1 LASTPIN (-3300 4000) BN 4
J 0
(-3312 4008);
DISPLAY 0.489362 (-3312 4008);
PAINT GREEN (-3312 4008);
FORCEPROP 2 LAST CDS_LIB mstr_standard
J 0
(-3250 4000);
DISPLAY 0.723404 (-3250 4000);
PAINT MONO (-3250 4000);
DISPLAY INVISIBLE (-3250 4000);
FORCEPROP 1 LAST BODY_TYPE PLUMBING
J 0
(-3250 4050);
DISPLAY 0.872340 (-3250 4050);
PAINT GREEN (-3250 4050);
DISPLAY INVISIBLE (-3250 4050);
FORCEPROP 1 LAST HDL_TAP TRUE
J 0
(-2925 3875);
DISPLAY 0.872340 (-2925 3875);
DISPLAY INVISIBLE (-2925 3875);
FORCEPROP 1 LAST PATH I199
J 0
(-3252 4000);
DISPLAY 0.872340 (-3252 4000);
PAINT GREEN (-3252 4000);
DISPLAY INVISIBLE (-3252 4000);
FORCEADD TAP..1
(-3250 3850);
FORCEPROP 3 LASTPIN (-3300 3850) SIG_NAME M_J_CPU0_SB_DQ<7>
J 0
(-3290 3860);
DISPLAY 0.659574 (-3290 3860);
PAINT MONO (-3290 3860);
DISPLAY INVISIBLE (-3290 3860);
FORCEPROP 1 LASTPIN (-3300 3850) BN 7
J 0
(-3312 3858);
DISPLAY 0.489362 (-3312 3858);
PAINT GREEN (-3312 3858);
FORCEPROP 2 LAST CDS_LIB mstr_standard
J 0
(-3250 3850);
DISPLAY 0.723404 (-3250 3850);
PAINT MONO (-3250 3850);
DISPLAY INVISIBLE (-3250 3850);
FORCEPROP 1 LAST BODY_TYPE PLUMBING
J 0
(-3250 3900);
DISPLAY 0.872340 (-3250 3900);
PAINT GREEN (-3250 3900);
DISPLAY INVISIBLE (-3250 3900);
FORCEPROP 1 LAST HDL_TAP TRUE
J 0
(-2925 3725);
DISPLAY 0.872340 (-2925 3725);
DISPLAY INVISIBLE (-2925 3725);
FORCEPROP 1 LAST PATH I200
J 0
(-3252 3850);
DISPLAY 0.872340 (-3252 3850);
PAINT GREEN (-3252 3850);
DISPLAY INVISIBLE (-3252 3850);
FORCEADD TAP..1
(-3250 3900);
FORCEPROP 3 LASTPIN (-3300 3900) SIG_NAME M_J_CPU0_SB_DQ<6>
J 0
(-3290 3910);
DISPLAY 0.659574 (-3290 3910);
PAINT MONO (-3290 3910);
DISPLAY INVISIBLE (-3290 3910);
FORCEPROP 1 LASTPIN (-3300 3900) BN 6
J 0
(-3312 3908);
DISPLAY 0.489362 (-3312 3908);
PAINT GREEN (-3312 3908);
FORCEPROP 2 LAST CDS_LIB mstr_standard
J 0
(-3250 3900);
DISPLAY 0.723404 (-3250 3900);
PAINT MONO (-3250 3900);
DISPLAY INVISIBLE (-3250 3900);
FORCEPROP 1 LAST BODY_TYPE PLUMBING
J 0
(-3250 3950);
DISPLAY 0.872340 (-3250 3950);
PAINT GREEN (-3250 3950);
DISPLAY INVISIBLE (-3250 3950);
FORCEPROP 1 LAST HDL_TAP TRUE
J 0
(-2925 3775);
DISPLAY 0.872340 (-2925 3775);
DISPLAY INVISIBLE (-2925 3775);
FORCEPROP 1 LAST PATH I201
J 0
(-3252 3900);
DISPLAY 0.872340 (-3252 3900);
PAINT GREEN (-3252 3900);
DISPLAY INVISIBLE (-3252 3900);
FORCEADD TAP..1
(-3250 3950);
FORCEPROP 3 LASTPIN (-3300 3950) SIG_NAME M_J_CPU0_SB_DQ<5>
J 0
(-3290 3960);
DISPLAY 0.659574 (-3290 3960);
PAINT MONO (-3290 3960);
DISPLAY INVISIBLE (-3290 3960);
FORCEPROP 1 LASTPIN (-3300 3950) BN 5
J 0
(-3312 3958);
DISPLAY 0.489362 (-3312 3958);
PAINT GREEN (-3312 3958);
FORCEPROP 2 LAST CDS_LIB mstr_standard
J 0
(-3250 3950);
DISPLAY 0.723404 (-3250 3950);
PAINT MONO (-3250 3950);
DISPLAY INVISIBLE (-3250 3950);
FORCEPROP 1 LAST BODY_TYPE PLUMBING
J 0
(-3250 4000);
DISPLAY 0.872340 (-3250 4000);
PAINT GREEN (-3250 4000);
DISPLAY INVISIBLE (-3250 4000);
FORCEPROP 1 LAST HDL_TAP TRUE
J 0
(-2925 3825);
DISPLAY 0.872340 (-2925 3825);
DISPLAY INVISIBLE (-2925 3825);
FORCEPROP 1 LAST PATH I202
J 0
(-3252 3950);
DISPLAY 0.872340 (-3252 3950);
PAINT GREEN (-3252 3950);
DISPLAY INVISIBLE (-3252 3950);
FORCEADD TAP..1
(-3250 3750);
FORCEPROP 3 LASTPIN (-3300 3750) SIG_NAME M_J_CPU0_SB_DQ<8>
J 0
(-3290 3760);
DISPLAY 0.659574 (-3290 3760);
PAINT MONO (-3290 3760);
DISPLAY INVISIBLE (-3290 3760);
FORCEPROP 1 LASTPIN (-3300 3750) BN 8
J 0
(-3312 3758);
DISPLAY 0.489362 (-3312 3758);
PAINT GREEN (-3312 3758);
FORCEPROP 2 LAST CDS_LIB mstr_standard
J 0
(-3250 3750);
DISPLAY 0.723404 (-3250 3750);
PAINT MONO (-3250 3750);
DISPLAY INVISIBLE (-3250 3750);
FORCEPROP 1 LAST BODY_TYPE PLUMBING
J 0
(-3250 3800);
DISPLAY 0.872340 (-3250 3800);
PAINT GREEN (-3250 3800);
DISPLAY INVISIBLE (-3250 3800);
FORCEPROP 1 LAST HDL_TAP TRUE
J 0
(-2925 3625);
DISPLAY 0.872340 (-2925 3625);
DISPLAY INVISIBLE (-2925 3625);
FORCEPROP 1 LAST PATH I203
J 0
(-3252 3750);
DISPLAY 0.872340 (-3252 3750);
PAINT GREEN (-3252 3750);
DISPLAY INVISIBLE (-3252 3750);
FORCEADD TAP..1
(-3250 3700);
FORCEPROP 3 LASTPIN (-3300 3700) SIG_NAME M_J_CPU0_SB_DQ<9>
J 0
(-3290 3710);
DISPLAY 0.659574 (-3290 3710);
PAINT MONO (-3290 3710);
DISPLAY INVISIBLE (-3290 3710);
FORCEPROP 1 LASTPIN (-3300 3700) BN 9
J 0
(-3312 3708);
DISPLAY 0.489362 (-3312 3708);
PAINT GREEN (-3312 3708);
FORCEPROP 2 LAST CDS_LIB mstr_standard
J 0
(-3250 3700);
DISPLAY 0.723404 (-3250 3700);
PAINT MONO (-3250 3700);
DISPLAY INVISIBLE (-3250 3700);
FORCEPROP 1 LAST BODY_TYPE PLUMBING
J 0
(-3250 3750);
DISPLAY 0.872340 (-3250 3750);
PAINT GREEN (-3250 3750);
DISPLAY INVISIBLE (-3250 3750);
FORCEPROP 1 LAST HDL_TAP TRUE
J 0
(-2925 3575);
DISPLAY 0.872340 (-2925 3575);
DISPLAY INVISIBLE (-2925 3575);
FORCEPROP 1 LAST PATH I204
J 0
(-3252 3700);
DISPLAY 0.872340 (-3252 3700);
PAINT GREEN (-3252 3700);
DISPLAY INVISIBLE (-3252 3700);
FORCEADD TAP..1
(-3250 3650);
FORCEPROP 3 LASTPIN (-3300 3650) SIG_NAME M_J_CPU0_SB_DQ<10>
J 0
(-3290 3660);
DISPLAY 0.659574 (-3290 3660);
PAINT MONO (-3290 3660);
DISPLAY INVISIBLE (-3290 3660);
FORCEPROP 1 LASTPIN (-3300 3650) BN 10
J 0
(-3312 3658);
DISPLAY 0.489362 (-3312 3658);
PAINT GREEN (-3312 3658);
FORCEPROP 2 LAST CDS_LIB mstr_standard
J 0
(-3250 3650);
DISPLAY 0.723404 (-3250 3650);
PAINT MONO (-3250 3650);
DISPLAY INVISIBLE (-3250 3650);
FORCEPROP 1 LAST BODY_TYPE PLUMBING
J 0
(-3250 3700);
DISPLAY 0.872340 (-3250 3700);
PAINT GREEN (-3250 3700);
DISPLAY INVISIBLE (-3250 3700);
FORCEPROP 1 LAST HDL_TAP TRUE
J 0
(-2925 3525);
DISPLAY 0.872340 (-2925 3525);
DISPLAY INVISIBLE (-2925 3525);
FORCEPROP 1 LAST PATH I205
J 0
(-3252 3650);
DISPLAY 0.872340 (-3252 3650);
PAINT GREEN (-3252 3650);
DISPLAY INVISIBLE (-3252 3650);
FORCEADD TAP..1
(-3250 3600);
FORCEPROP 3 LASTPIN (-3300 3600) SIG_NAME M_J_CPU0_SB_DQ<11>
J 0
(-3290 3610);
DISPLAY 0.659574 (-3290 3610);
PAINT MONO (-3290 3610);
DISPLAY INVISIBLE (-3290 3610);
FORCEPROP 1 LASTPIN (-3300 3600) BN 11
J 0
(-3312 3608);
DISPLAY 0.489362 (-3312 3608);
PAINT GREEN (-3312 3608);
FORCEPROP 2 LAST CDS_LIB mstr_standard
J 0
(-3250 3600);
DISPLAY 0.723404 (-3250 3600);
PAINT MONO (-3250 3600);
DISPLAY INVISIBLE (-3250 3600);
FORCEPROP 1 LAST BODY_TYPE PLUMBING
J 0
(-3250 3650);
DISPLAY 0.872340 (-3250 3650);
PAINT GREEN (-3250 3650);
DISPLAY INVISIBLE (-3250 3650);
FORCEPROP 1 LAST HDL_TAP TRUE
J 0
(-2925 3475);
DISPLAY 0.872340 (-2925 3475);
DISPLAY INVISIBLE (-2925 3475);
FORCEPROP 1 LAST PATH I206
J 0
(-3252 3600);
DISPLAY 0.872340 (-3252 3600);
PAINT GREEN (-3252 3600);
DISPLAY INVISIBLE (-3252 3600);
FORCEADD TAP..1
(-3250 3500);
FORCEPROP 3 LASTPIN (-3300 3500) SIG_NAME M_J_CPU0_SB_DQ<13>
J 0
(-3290 3510);
DISPLAY 0.659574 (-3290 3510);
PAINT MONO (-3290 3510);
DISPLAY INVISIBLE (-3290 3510);
FORCEPROP 1 LASTPIN (-3300 3500) BN 13
J 0
(-3312 3508);
DISPLAY 0.489362 (-3312 3508);
PAINT GREEN (-3312 3508);
FORCEPROP 2 LAST CDS_LIB mstr_standard
J 0
(-3250 3500);
DISPLAY 0.723404 (-3250 3500);
PAINT MONO (-3250 3500);
DISPLAY INVISIBLE (-3250 3500);
FORCEPROP 1 LAST BODY_TYPE PLUMBING
J 0
(-3250 3550);
DISPLAY 0.872340 (-3250 3550);
PAINT GREEN (-3250 3550);
DISPLAY INVISIBLE (-3250 3550);
FORCEPROP 1 LAST HDL_TAP TRUE
J 0
(-2925 3375);
DISPLAY 0.872340 (-2925 3375);
DISPLAY INVISIBLE (-2925 3375);
FORCEPROP 1 LAST PATH I207
J 0
(-3252 3500);
DISPLAY 0.872340 (-3252 3500);
PAINT GREEN (-3252 3500);
DISPLAY INVISIBLE (-3252 3500);
FORCEADD TAP..1
(-3250 3550);
FORCEPROP 3 LASTPIN (-3300 3550) SIG_NAME M_J_CPU0_SB_DQ<12>
J 0
(-3290 3560);
DISPLAY 0.659574 (-3290 3560);
PAINT MONO (-3290 3560);
DISPLAY INVISIBLE (-3290 3560);
FORCEPROP 1 LASTPIN (-3300 3550) BN 12
J 0
(-3312 3558);
DISPLAY 0.489362 (-3312 3558);
PAINT GREEN (-3312 3558);
FORCEPROP 2 LAST CDS_LIB mstr_standard
J 0
(-3250 3550);
DISPLAY 0.723404 (-3250 3550);
PAINT MONO (-3250 3550);
DISPLAY INVISIBLE (-3250 3550);
FORCEPROP 1 LAST BODY_TYPE PLUMBING
J 0
(-3250 3600);
DISPLAY 0.872340 (-3250 3600);
PAINT GREEN (-3250 3600);
DISPLAY INVISIBLE (-3250 3600);
FORCEPROP 1 LAST HDL_TAP TRUE
J 0
(-2925 3425);
DISPLAY 0.872340 (-2925 3425);
DISPLAY INVISIBLE (-2925 3425);
FORCEPROP 1 LAST PATH I208
J 0
(-3252 3550);
DISPLAY 0.872340 (-3252 3550);
PAINT GREEN (-3252 3550);
DISPLAY INVISIBLE (-3252 3550);
FORCEADD TAP..1
(-3250 3400);
FORCEPROP 3 LASTPIN (-3300 3400) SIG_NAME M_J_CPU0_SB_DQ<15>
J 0
(-3290 3410);
DISPLAY 0.659574 (-3290 3410);
PAINT MONO (-3290 3410);
DISPLAY INVISIBLE (-3290 3410);
FORCEPROP 1 LASTPIN (-3300 3400) BN 15
J 0
(-3312 3408);
DISPLAY 0.489362 (-3312 3408);
PAINT GREEN (-3312 3408);
FORCEPROP 2 LAST CDS_LIB mstr_standard
J 0
(-3250 3400);
DISPLAY 0.723404 (-3250 3400);
PAINT MONO (-3250 3400);
DISPLAY INVISIBLE (-3250 3400);
FORCEPROP 1 LAST BODY_TYPE PLUMBING
J 0
(-3250 3450);
DISPLAY 0.872340 (-3250 3450);
PAINT GREEN (-3250 3450);
DISPLAY INVISIBLE (-3250 3450);
FORCEPROP 1 LAST HDL_TAP TRUE
J 0
(-2925 3275);
DISPLAY 0.872340 (-2925 3275);
DISPLAY INVISIBLE (-2925 3275);
FORCEPROP 1 LAST PATH I209
J 0
(-3252 3400);
DISPLAY 0.872340 (-3252 3400);
PAINT GREEN (-3252 3400);
DISPLAY INVISIBLE (-3252 3400);
FORCEADD TAP..1
(-3250 3450);
FORCEPROP 3 LASTPIN (-3300 3450) SIG_NAME M_J_CPU0_SB_DQ<14>
J 0
(-3290 3460);
DISPLAY 0.659574 (-3290 3460);
PAINT MONO (-3290 3460);
DISPLAY INVISIBLE (-3290 3460);
FORCEPROP 1 LASTPIN (-3300 3450) BN 14
J 0
(-3312 3458);
DISPLAY 0.489362 (-3312 3458);
PAINT GREEN (-3312 3458);
FORCEPROP 2 LAST CDS_LIB mstr_standard
J 0
(-3250 3450);
DISPLAY 0.723404 (-3250 3450);
PAINT MONO (-3250 3450);
DISPLAY INVISIBLE (-3250 3450);
FORCEPROP 1 LAST BODY_TYPE PLUMBING
J 0
(-3250 3500);
DISPLAY 0.872340 (-3250 3500);
PAINT GREEN (-3250 3500);
DISPLAY INVISIBLE (-3250 3500);
FORCEPROP 1 LAST HDL_TAP TRUE
J 0
(-2925 3325);
DISPLAY 0.872340 (-2925 3325);
DISPLAY INVISIBLE (-2925 3325);
FORCEPROP 1 LAST PATH I210
J 0
(-3252 3450);
DISPLAY 0.872340 (-3252 3450);
PAINT GREEN (-3252 3450);
DISPLAY INVISIBLE (-3252 3450);
FORCEADD TAP..1
(-3250 3250);
FORCEPROP 3 LASTPIN (-3300 3250) SIG_NAME M_J_CPU0_SB_DQ<17>
J 0
(-3290 3260);
DISPLAY 0.659574 (-3290 3260);
PAINT MONO (-3290 3260);
DISPLAY INVISIBLE (-3290 3260);
FORCEPROP 1 LASTPIN (-3300 3250) BN 17
J 0
(-3312 3258);
DISPLAY 0.489362 (-3312 3258);
PAINT GREEN (-3312 3258);
FORCEPROP 2 LAST CDS_LIB mstr_standard
J 0
(-3250 3250);
DISPLAY 0.723404 (-3250 3250);
PAINT MONO (-3250 3250);
DISPLAY INVISIBLE (-3250 3250);
FORCEPROP 1 LAST BODY_TYPE PLUMBING
J 0
(-3250 3300);
DISPLAY 0.872340 (-3250 3300);
PAINT GREEN (-3250 3300);
DISPLAY INVISIBLE (-3250 3300);
FORCEPROP 1 LAST HDL_TAP TRUE
J 0
(-2925 3125);
DISPLAY 0.872340 (-2925 3125);
DISPLAY INVISIBLE (-2925 3125);
FORCEPROP 1 LAST PATH I211
J 0
(-3252 3250);
DISPLAY 0.872340 (-3252 3250);
PAINT GREEN (-3252 3250);
DISPLAY INVISIBLE (-3252 3250);
FORCEADD TAP..1
(-3250 3300);
FORCEPROP 3 LASTPIN (-3300 3300) SIG_NAME M_J_CPU0_SB_DQ<16>
J 0
(-3290 3310);
DISPLAY 0.659574 (-3290 3310);
PAINT MONO (-3290 3310);
DISPLAY INVISIBLE (-3290 3310);
FORCEPROP 1 LASTPIN (-3300 3300) BN 16
J 0
(-3312 3308);
DISPLAY 0.489362 (-3312 3308);
PAINT GREEN (-3312 3308);
FORCEPROP 2 LAST CDS_LIB mstr_standard
J 0
(-3250 3300);
DISPLAY 0.723404 (-3250 3300);
PAINT MONO (-3250 3300);
DISPLAY INVISIBLE (-3250 3300);
FORCEPROP 1 LAST BODY_TYPE PLUMBING
J 0
(-3250 3350);
DISPLAY 0.872340 (-3250 3350);
PAINT GREEN (-3250 3350);
DISPLAY INVISIBLE (-3250 3350);
FORCEPROP 1 LAST HDL_TAP TRUE
J 0
(-2925 3175);
DISPLAY 0.872340 (-2925 3175);
DISPLAY INVISIBLE (-2925 3175);
FORCEPROP 1 LAST PATH I212
J 0
(-3252 3300);
DISPLAY 0.872340 (-3252 3300);
PAINT GREEN (-3252 3300);
DISPLAY INVISIBLE (-3252 3300);
FORCEADD TAP..1
(-3250 3200);
FORCEPROP 3 LASTPIN (-3300 3200) SIG_NAME M_J_CPU0_SB_DQ<18>
J 0
(-3290 3210);
DISPLAY 0.659574 (-3290 3210);
PAINT MONO (-3290 3210);
DISPLAY INVISIBLE (-3290 3210);
FORCEPROP 1 LASTPIN (-3300 3200) BN 18
J 0
(-3312 3208);
DISPLAY 0.489362 (-3312 3208);
PAINT GREEN (-3312 3208);
FORCEPROP 2 LAST CDS_LIB mstr_standard
J 0
(-3250 3200);
DISPLAY 0.723404 (-3250 3200);
PAINT MONO (-3250 3200);
DISPLAY INVISIBLE (-3250 3200);
FORCEPROP 1 LAST BODY_TYPE PLUMBING
J 0
(-3250 3250);
DISPLAY 0.872340 (-3250 3250);
PAINT GREEN (-3250 3250);
DISPLAY INVISIBLE (-3250 3250);
FORCEPROP 1 LAST HDL_TAP TRUE
J 0
(-2925 3075);
DISPLAY 0.872340 (-2925 3075);
DISPLAY INVISIBLE (-2925 3075);
FORCEPROP 1 LAST PATH I213
J 0
(-3252 3200);
DISPLAY 0.872340 (-3252 3200);
PAINT GREEN (-3252 3200);
DISPLAY INVISIBLE (-3252 3200);
FORCEADD TAP..1
(-3250 3100);
FORCEPROP 3 LASTPIN (-3300 3100) SIG_NAME M_J_CPU0_SB_DQ<20>
J 0
(-3290 3110);
DISPLAY 0.659574 (-3290 3110);
PAINT MONO (-3290 3110);
DISPLAY INVISIBLE (-3290 3110);
FORCEPROP 1 LASTPIN (-3300 3100) BN 20
J 0
(-3312 3108);
DISPLAY 0.489362 (-3312 3108);
PAINT GREEN (-3312 3108);
FORCEPROP 2 LAST CDS_LIB mstr_standard
J 0
(-3250 3100);
DISPLAY 0.723404 (-3250 3100);
PAINT MONO (-3250 3100);
DISPLAY INVISIBLE (-3250 3100);
FORCEPROP 1 LAST BODY_TYPE PLUMBING
J 0
(-3250 3150);
DISPLAY 0.872340 (-3250 3150);
PAINT GREEN (-3250 3150);
DISPLAY INVISIBLE (-3250 3150);
FORCEPROP 1 LAST HDL_TAP TRUE
J 0
(-2925 2975);
DISPLAY 0.872340 (-2925 2975);
DISPLAY INVISIBLE (-2925 2975);
FORCEPROP 1 LAST PATH I214
J 0
(-3252 3100);
DISPLAY 0.872340 (-3252 3100);
PAINT GREEN (-3252 3100);
DISPLAY INVISIBLE (-3252 3100);
FORCEADD TAP..1
(-3250 3150);
FORCEPROP 3 LASTPIN (-3300 3150) SIG_NAME M_J_CPU0_SB_DQ<19>
J 0
(-3290 3160);
DISPLAY 0.659574 (-3290 3160);
PAINT MONO (-3290 3160);
DISPLAY INVISIBLE (-3290 3160);
FORCEPROP 1 LASTPIN (-3300 3150) BN 19
J 0
(-3312 3158);
DISPLAY 0.489362 (-3312 3158);
PAINT GREEN (-3312 3158);
FORCEPROP 2 LAST CDS_LIB mstr_standard
J 0
(-3250 3150);
DISPLAY 0.723404 (-3250 3150);
PAINT MONO (-3250 3150);
DISPLAY INVISIBLE (-3250 3150);
FORCEPROP 1 LAST BODY_TYPE PLUMBING
J 0
(-3250 3200);
DISPLAY 0.872340 (-3250 3200);
PAINT GREEN (-3250 3200);
DISPLAY INVISIBLE (-3250 3200);
FORCEPROP 1 LAST HDL_TAP TRUE
J 0
(-2925 3025);
DISPLAY 0.872340 (-2925 3025);
DISPLAY INVISIBLE (-2925 3025);
FORCEPROP 1 LAST PATH I215
J 0
(-3252 3150);
DISPLAY 0.872340 (-3252 3150);
PAINT GREEN (-3252 3150);
DISPLAY INVISIBLE (-3252 3150);
FORCEADD TAP..1
(-3250 2950);
FORCEPROP 3 LASTPIN (-3300 2950) SIG_NAME M_J_CPU0_SB_DQ<23>
J 0
(-3290 2960);
DISPLAY 0.659574 (-3290 2960);
PAINT MONO (-3290 2960);
DISPLAY INVISIBLE (-3290 2960);
FORCEPROP 1 LASTPIN (-3300 2950) BN 23
J 0
(-3312 2958);
DISPLAY 0.489362 (-3312 2958);
PAINT GREEN (-3312 2958);
FORCEPROP 2 LAST CDS_LIB mstr_standard
J 0
(-3250 2950);
DISPLAY 0.723404 (-3250 2950);
PAINT MONO (-3250 2950);
DISPLAY INVISIBLE (-3250 2950);
FORCEPROP 1 LAST BODY_TYPE PLUMBING
J 0
(-3250 3000);
DISPLAY 0.872340 (-3250 3000);
PAINT GREEN (-3250 3000);
DISPLAY INVISIBLE (-3250 3000);
FORCEPROP 1 LAST HDL_TAP TRUE
J 0
(-2925 2825);
DISPLAY 0.872340 (-2925 2825);
DISPLAY INVISIBLE (-2925 2825);
FORCEPROP 1 LAST PATH I216
J 0
(-3252 2950);
DISPLAY 0.872340 (-3252 2950);
PAINT GREEN (-3252 2950);
DISPLAY INVISIBLE (-3252 2950);
FORCEADD TAP..1
(-3250 3000);
FORCEPROP 3 LASTPIN (-3300 3000) SIG_NAME M_J_CPU0_SB_DQ<22>
J 0
(-3290 3010);
DISPLAY 0.659574 (-3290 3010);
PAINT MONO (-3290 3010);
DISPLAY INVISIBLE (-3290 3010);
FORCEPROP 1 LASTPIN (-3300 3000) BN 22
J 0
(-3312 3008);
DISPLAY 0.489362 (-3312 3008);
PAINT GREEN (-3312 3008);
FORCEPROP 2 LAST CDS_LIB mstr_standard
J 0
(-3250 3000);
DISPLAY 0.723404 (-3250 3000);
PAINT MONO (-3250 3000);
DISPLAY INVISIBLE (-3250 3000);
FORCEPROP 1 LAST BODY_TYPE PLUMBING
J 0
(-3250 3050);
DISPLAY 0.872340 (-3250 3050);
PAINT GREEN (-3250 3050);
DISPLAY INVISIBLE (-3250 3050);
FORCEPROP 1 LAST HDL_TAP TRUE
J 0
(-2925 2875);
DISPLAY 0.872340 (-2925 2875);
DISPLAY INVISIBLE (-2925 2875);
FORCEPROP 1 LAST PATH I217
J 0
(-3252 3000);
DISPLAY 0.872340 (-3252 3000);
PAINT GREEN (-3252 3000);
DISPLAY INVISIBLE (-3252 3000);
FORCEADD TAP..1
(-3250 3050);
FORCEPROP 3 LASTPIN (-3300 3050) SIG_NAME M_J_CPU0_SB_DQ<21>
J 0
(-3290 3060);
DISPLAY 0.659574 (-3290 3060);
PAINT MONO (-3290 3060);
DISPLAY INVISIBLE (-3290 3060);
FORCEPROP 1 LASTPIN (-3300 3050) BN 21
J 0
(-3312 3058);
DISPLAY 0.489362 (-3312 3058);
PAINT GREEN (-3312 3058);
FORCEPROP 2 LAST CDS_LIB mstr_standard
J 0
(-3250 3050);
DISPLAY 0.723404 (-3250 3050);
PAINT MONO (-3250 3050);
DISPLAY INVISIBLE (-3250 3050);
FORCEPROP 1 LAST BODY_TYPE PLUMBING
J 0
(-3250 3100);
DISPLAY 0.872340 (-3250 3100);
PAINT GREEN (-3250 3100);
DISPLAY INVISIBLE (-3250 3100);
FORCEPROP 1 LAST HDL_TAP TRUE
J 0
(-2925 2925);
DISPLAY 0.872340 (-2925 2925);
DISPLAY INVISIBLE (-2925 2925);
FORCEPROP 1 LAST PATH I218
J 0
(-3252 3050);
DISPLAY 0.872340 (-3252 3050);
PAINT GREEN (-3252 3050);
DISPLAY INVISIBLE (-3252 3050);
FORCEADD TAP..1
(-3250 2850);
FORCEPROP 3 LASTPIN (-3300 2850) SIG_NAME M_J_CPU0_SB_DQ<24>
J 0
(-3290 2860);
DISPLAY 0.659574 (-3290 2860);
PAINT MONO (-3290 2860);
DISPLAY INVISIBLE (-3290 2860);
FORCEPROP 1 LASTPIN (-3300 2850) BN 24
J 0
(-3312 2858);
DISPLAY 0.489362 (-3312 2858);
PAINT GREEN (-3312 2858);
FORCEPROP 2 LAST CDS_LIB mstr_standard
J 0
(-3250 2850);
DISPLAY 0.723404 (-3250 2850);
PAINT MONO (-3250 2850);
DISPLAY INVISIBLE (-3250 2850);
FORCEPROP 1 LAST BODY_TYPE PLUMBING
J 0
(-3250 2900);
DISPLAY 0.872340 (-3250 2900);
PAINT GREEN (-3250 2900);
DISPLAY INVISIBLE (-3250 2900);
FORCEPROP 1 LAST HDL_TAP TRUE
J 0
(-2925 2725);
DISPLAY 0.872340 (-2925 2725);
DISPLAY INVISIBLE (-2925 2725);
FORCEPROP 1 LAST PATH I219
J 0
(-3252 2850);
DISPLAY 0.872340 (-3252 2850);
PAINT GREEN (-3252 2850);
DISPLAY INVISIBLE (-3252 2850);
FORCEADD TAP..1
(-3250 2800);
FORCEPROP 3 LASTPIN (-3300 2800) SIG_NAME M_J_CPU0_SB_DQ<25>
J 0
(-3290 2810);
DISPLAY 0.659574 (-3290 2810);
PAINT MONO (-3290 2810);
DISPLAY INVISIBLE (-3290 2810);
FORCEPROP 1 LASTPIN (-3300 2800) BN 25
J 0
(-3312 2808);
DISPLAY 0.489362 (-3312 2808);
PAINT GREEN (-3312 2808);
FORCEPROP 2 LAST CDS_LIB mstr_standard
J 0
(-3250 2800);
DISPLAY 0.723404 (-3250 2800);
PAINT MONO (-3250 2800);
DISPLAY INVISIBLE (-3250 2800);
FORCEPROP 1 LAST BODY_TYPE PLUMBING
J 0
(-3250 2850);
DISPLAY 0.872340 (-3250 2850);
PAINT GREEN (-3250 2850);
DISPLAY INVISIBLE (-3250 2850);
FORCEPROP 1 LAST HDL_TAP TRUE
J 0
(-2925 2675);
DISPLAY 0.872340 (-2925 2675);
DISPLAY INVISIBLE (-2925 2675);
FORCEPROP 1 LAST PATH I220
J 0
(-3252 2800);
DISPLAY 0.872340 (-3252 2800);
PAINT GREEN (-3252 2800);
DISPLAY INVISIBLE (-3252 2800);
FORCEADD TAP..1
(-3250 2750);
FORCEPROP 3 LASTPIN (-3300 2750) SIG_NAME M_J_CPU0_SB_DQ<26>
J 0
(-3290 2760);
DISPLAY 0.659574 (-3290 2760);
PAINT MONO (-3290 2760);
DISPLAY INVISIBLE (-3290 2760);
FORCEPROP 1 LASTPIN (-3300 2750) BN 26
J 0
(-3312 2758);
DISPLAY 0.489362 (-3312 2758);
PAINT GREEN (-3312 2758);
FORCEPROP 2 LAST CDS_LIB mstr_standard
J 0
(-3250 2750);
DISPLAY 0.723404 (-3250 2750);
PAINT MONO (-3250 2750);
DISPLAY INVISIBLE (-3250 2750);
FORCEPROP 1 LAST BODY_TYPE PLUMBING
J 0
(-3250 2800);
DISPLAY 0.872340 (-3250 2800);
PAINT GREEN (-3250 2800);
DISPLAY INVISIBLE (-3250 2800);
FORCEPROP 1 LAST HDL_TAP TRUE
J 0
(-2925 2625);
DISPLAY 0.872340 (-2925 2625);
DISPLAY INVISIBLE (-2925 2625);
FORCEPROP 1 LAST PATH I221
J 0
(-3252 2750);
DISPLAY 0.872340 (-3252 2750);
PAINT GREEN (-3252 2750);
DISPLAY INVISIBLE (-3252 2750);
FORCEADD TAP..1
(-3250 2700);
FORCEPROP 3 LASTPIN (-3300 2700) SIG_NAME M_J_CPU0_SB_DQ<27>
J 0
(-3290 2710);
DISPLAY 0.659574 (-3290 2710);
PAINT MONO (-3290 2710);
DISPLAY INVISIBLE (-3290 2710);
FORCEPROP 1 LASTPIN (-3300 2700) BN 27
J 0
(-3312 2708);
DISPLAY 0.489362 (-3312 2708);
PAINT GREEN (-3312 2708);
FORCEPROP 2 LAST CDS_LIB mstr_standard
J 0
(-3250 2700);
DISPLAY 0.723404 (-3250 2700);
PAINT MONO (-3250 2700);
DISPLAY INVISIBLE (-3250 2700);
FORCEPROP 1 LAST BODY_TYPE PLUMBING
J 0
(-3250 2750);
DISPLAY 0.872340 (-3250 2750);
PAINT GREEN (-3250 2750);
DISPLAY INVISIBLE (-3250 2750);
FORCEPROP 1 LAST HDL_TAP TRUE
J 0
(-2925 2575);
DISPLAY 0.872340 (-2925 2575);
DISPLAY INVISIBLE (-2925 2575);
FORCEPROP 1 LAST PATH I222
J 0
(-3252 2700);
DISPLAY 0.872340 (-3252 2700);
PAINT GREEN (-3252 2700);
DISPLAY INVISIBLE (-3252 2700);
FORCEADD TAP..1
(-3250 2650);
FORCEPROP 3 LASTPIN (-3300 2650) SIG_NAME M_J_CPU0_SB_DQ<28>
J 0
(-3290 2660);
DISPLAY 0.659574 (-3290 2660);
PAINT MONO (-3290 2660);
DISPLAY INVISIBLE (-3290 2660);
FORCEPROP 1 LASTPIN (-3300 2650) BN 28
J 0
(-3312 2658);
DISPLAY 0.489362 (-3312 2658);
PAINT GREEN (-3312 2658);
FORCEPROP 2 LAST CDS_LIB mstr_standard
J 0
(-3250 2650);
DISPLAY 0.723404 (-3250 2650);
PAINT MONO (-3250 2650);
DISPLAY INVISIBLE (-3250 2650);
FORCEPROP 1 LAST BODY_TYPE PLUMBING
J 0
(-3250 2700);
DISPLAY 0.872340 (-3250 2700);
PAINT GREEN (-3250 2700);
DISPLAY INVISIBLE (-3250 2700);
FORCEPROP 1 LAST HDL_TAP TRUE
J 0
(-2925 2525);
DISPLAY 0.872340 (-2925 2525);
DISPLAY INVISIBLE (-2925 2525);
FORCEPROP 1 LAST PATH I223
J 0
(-3252 2650);
DISPLAY 0.872340 (-3252 2650);
PAINT GREEN (-3252 2650);
DISPLAY INVISIBLE (-3252 2650);
FORCEADD TAP..1
(-3250 2600);
FORCEPROP 3 LASTPIN (-3300 2600) SIG_NAME M_J_CPU0_SB_DQ<29>
J 0
(-3290 2610);
DISPLAY 0.659574 (-3290 2610);
PAINT MONO (-3290 2610);
DISPLAY INVISIBLE (-3290 2610);
FORCEPROP 1 LASTPIN (-3300 2600) BN 29
J 0
(-3312 2608);
DISPLAY 0.489362 (-3312 2608);
PAINT GREEN (-3312 2608);
FORCEPROP 2 LAST CDS_LIB mstr_standard
J 0
(-3250 2600);
DISPLAY 0.723404 (-3250 2600);
PAINT MONO (-3250 2600);
DISPLAY INVISIBLE (-3250 2600);
FORCEPROP 1 LAST BODY_TYPE PLUMBING
J 0
(-3250 2650);
DISPLAY 0.872340 (-3250 2650);
PAINT GREEN (-3250 2650);
DISPLAY INVISIBLE (-3250 2650);
FORCEPROP 1 LAST HDL_TAP TRUE
J 0
(-2925 2475);
DISPLAY 0.872340 (-2925 2475);
DISPLAY INVISIBLE (-2925 2475);
FORCEPROP 1 LAST PATH I224
J 0
(-3252 2600);
DISPLAY 0.872340 (-3252 2600);
PAINT GREEN (-3252 2600);
DISPLAY INVISIBLE (-3252 2600);
FORCEADD TAP..1
(-3250 2550);
FORCEPROP 3 LASTPIN (-3300 2550) SIG_NAME M_J_CPU0_SB_DQ<30>
J 0
(-3290 2560);
DISPLAY 0.659574 (-3290 2560);
PAINT MONO (-3290 2560);
DISPLAY INVISIBLE (-3290 2560);
FORCEPROP 1 LASTPIN (-3300 2550) BN 30
J 0
(-3312 2558);
DISPLAY 0.489362 (-3312 2558);
PAINT GREEN (-3312 2558);
FORCEPROP 2 LAST CDS_LIB mstr_standard
J 0
(-3250 2550);
DISPLAY 0.723404 (-3250 2550);
PAINT MONO (-3250 2550);
DISPLAY INVISIBLE (-3250 2550);
FORCEPROP 1 LAST BODY_TYPE PLUMBING
J 0
(-3250 2600);
DISPLAY 0.872340 (-3250 2600);
PAINT GREEN (-3250 2600);
DISPLAY INVISIBLE (-3250 2600);
FORCEPROP 1 LAST HDL_TAP TRUE
J 0
(-2925 2425);
DISPLAY 0.872340 (-2925 2425);
DISPLAY INVISIBLE (-2925 2425);
FORCEPROP 1 LAST PATH I225
J 0
(-3252 2550);
DISPLAY 0.872340 (-3252 2550);
PAINT GREEN (-3252 2550);
DISPLAY INVISIBLE (-3252 2550);
FORCEADD TAP..1
(-3250 2500);
FORCEPROP 3 LASTPIN (-3300 2500) SIG_NAME M_J_CPU0_SB_DQ<31>
J 0
(-3290 2510);
DISPLAY 0.659574 (-3290 2510);
PAINT MONO (-3290 2510);
DISPLAY INVISIBLE (-3290 2510);
FORCEPROP 1 LASTPIN (-3300 2500) BN 31
J 0
(-3312 2508);
DISPLAY 0.489362 (-3312 2508);
PAINT GREEN (-3312 2508);
FORCEPROP 2 LAST CDS_LIB mstr_standard
J 0
(-3250 2500);
DISPLAY 0.723404 (-3250 2500);
PAINT MONO (-3250 2500);
DISPLAY INVISIBLE (-3250 2500);
FORCEPROP 1 LAST BODY_TYPE PLUMBING
J 0
(-3250 2550);
DISPLAY 0.872340 (-3250 2550);
PAINT GREEN (-3250 2550);
DISPLAY INVISIBLE (-3250 2550);
FORCEPROP 1 LAST HDL_TAP TRUE
J 0
(-2925 2375);
DISPLAY 0.872340 (-2925 2375);
DISPLAY INVISIBLE (-2925 2375);
FORCEPROP 1 LAST PATH I226
J 0
(-3252 2500);
DISPLAY 0.872340 (-3252 2500);
PAINT GREEN (-3252 2500);
DISPLAY INVISIBLE (-3252 2500);
FORCEADD TAP..1
(-3250 2400);
FORCEPROP 3 LASTPIN (-3300 2400) SIG_NAME M_J_CPU0_SA_CB<0>
J 0
(-3290 2410);
DISPLAY 0.659574 (-3290 2410);
PAINT MONO (-3290 2410);
DISPLAY INVISIBLE (-3290 2410);
FORCEPROP 1 LASTPIN (-3300 2400) BN 0
J 0
(-3312 2408);
DISPLAY 0.489362 (-3312 2408);
PAINT GREEN (-3312 2408);
FORCEPROP 2 LAST CDS_LIB mstr_standard
J 2
(-3250 2400);
DISPLAY 0.723404 (-3250 2400);
PAINT MONO (-3250 2400);
DISPLAY INVISIBLE (-3250 2400);
FORCEPROP 1 LAST BODY_TYPE PLUMBING
J 0
(-3250 2450);
DISPLAY 0.872340 (-3250 2450);
PAINT GREEN (-3250 2450);
DISPLAY INVISIBLE (-3250 2450);
FORCEPROP 1 LAST HDL_TAP TRUE
J 0
(-2925 2275);
DISPLAY 0.872340 (-2925 2275);
DISPLAY INVISIBLE (-2925 2275);
FORCEPROP 1 LAST PATH I227
J 0
(-3252 2400);
DISPLAY 0.872340 (-3252 2400);
PAINT GREEN (-3252 2400);
DISPLAY INVISIBLE (-3252 2400);
FORCEADD TAP..1
(-3250 2350);
FORCEPROP 3 LASTPIN (-3300 2350) SIG_NAME M_J_CPU0_SA_CB<1>
J 0
(-3290 2360);
DISPLAY 0.659574 (-3290 2360);
PAINT MONO (-3290 2360);
DISPLAY INVISIBLE (-3290 2360);
FORCEPROP 1 LASTPIN (-3300 2350) BN 1
J 0
(-3312 2358);
DISPLAY 0.489362 (-3312 2358);
PAINT GREEN (-3312 2358);
FORCEPROP 2 LAST CDS_LIB mstr_standard
J 2
(-3250 2350);
DISPLAY 0.723404 (-3250 2350);
PAINT MONO (-3250 2350);
DISPLAY INVISIBLE (-3250 2350);
FORCEPROP 1 LAST BODY_TYPE PLUMBING
J 0
(-3250 2400);
DISPLAY 0.872340 (-3250 2400);
PAINT GREEN (-3250 2400);
DISPLAY INVISIBLE (-3250 2400);
FORCEPROP 1 LAST HDL_TAP TRUE
J 0
(-2925 2225);
DISPLAY 0.872340 (-2925 2225);
DISPLAY INVISIBLE (-2925 2225);
FORCEPROP 1 LAST PATH I228
J 0
(-3252 2350);
DISPLAY 0.872340 (-3252 2350);
PAINT GREEN (-3252 2350);
DISPLAY INVISIBLE (-3252 2350);
FORCEADD TAP..1
(-3250 2300);
FORCEPROP 3 LASTPIN (-3300 2300) SIG_NAME M_J_CPU0_SA_CB<2>
J 0
(-3290 2310);
DISPLAY 0.659574 (-3290 2310);
PAINT MONO (-3290 2310);
DISPLAY INVISIBLE (-3290 2310);
FORCEPROP 1 LASTPIN (-3300 2300) BN 2
J 0
(-3312 2308);
DISPLAY 0.489362 (-3312 2308);
PAINT GREEN (-3312 2308);
FORCEPROP 2 LAST CDS_LIB mstr_standard
J 2
(-3250 2300);
DISPLAY 0.723404 (-3250 2300);
PAINT MONO (-3250 2300);
DISPLAY INVISIBLE (-3250 2300);
FORCEPROP 1 LAST BODY_TYPE PLUMBING
J 0
(-3250 2350);
DISPLAY 0.872340 (-3250 2350);
PAINT GREEN (-3250 2350);
DISPLAY INVISIBLE (-3250 2350);
FORCEPROP 1 LAST HDL_TAP TRUE
J 0
(-2925 2175);
DISPLAY 0.872340 (-2925 2175);
DISPLAY INVISIBLE (-2925 2175);
FORCEPROP 1 LAST PATH I229
J 0
(-3252 2300);
DISPLAY 0.872340 (-3252 2300);
PAINT GREEN (-3252 2300);
DISPLAY INVISIBLE (-3252 2300);
FORCEADD TAP..1
(-3250 2250);
FORCEPROP 3 LASTPIN (-3300 2250) SIG_NAME M_J_CPU0_SA_CB<3>
J 0
(-3290 2260);
DISPLAY 0.659574 (-3290 2260);
PAINT MONO (-3290 2260);
DISPLAY INVISIBLE (-3290 2260);
FORCEPROP 1 LASTPIN (-3300 2250) BN 3
J 0
(-3312 2258);
DISPLAY 0.489362 (-3312 2258);
PAINT GREEN (-3312 2258);
FORCEPROP 2 LAST CDS_LIB mstr_standard
J 2
(-3250 2250);
DISPLAY 0.723404 (-3250 2250);
PAINT MONO (-3250 2250);
DISPLAY INVISIBLE (-3250 2250);
FORCEPROP 1 LAST BODY_TYPE PLUMBING
J 0
(-3250 2300);
DISPLAY 0.872340 (-3250 2300);
PAINT GREEN (-3250 2300);
DISPLAY INVISIBLE (-3250 2300);
FORCEPROP 1 LAST HDL_TAP TRUE
J 0
(-2925 2125);
DISPLAY 0.872340 (-2925 2125);
DISPLAY INVISIBLE (-2925 2125);
FORCEPROP 1 LAST PATH I230
J 0
(-3252 2250);
DISPLAY 0.872340 (-3252 2250);
PAINT GREEN (-3252 2250);
DISPLAY INVISIBLE (-3252 2250);
FORCEADD TAP..1
(-3250 2200);
FORCEPROP 3 LASTPIN (-3300 2200) SIG_NAME M_J_CPU0_SA_CB<4>
J 0
(-3290 2210);
DISPLAY 0.659574 (-3290 2210);
PAINT MONO (-3290 2210);
DISPLAY INVISIBLE (-3290 2210);
FORCEPROP 1 LASTPIN (-3300 2200) BN 4
J 0
(-3312 2208);
DISPLAY 0.489362 (-3312 2208);
PAINT GREEN (-3312 2208);
FORCEPROP 2 LAST CDS_LIB mstr_standard
J 2
(-3250 2200);
DISPLAY 0.723404 (-3250 2200);
PAINT MONO (-3250 2200);
DISPLAY INVISIBLE (-3250 2200);
FORCEPROP 1 LAST BODY_TYPE PLUMBING
J 0
(-3250 2250);
DISPLAY 0.872340 (-3250 2250);
PAINT GREEN (-3250 2250);
DISPLAY INVISIBLE (-3250 2250);
FORCEPROP 1 LAST HDL_TAP TRUE
J 0
(-2925 2075);
DISPLAY 0.872340 (-2925 2075);
DISPLAY INVISIBLE (-2925 2075);
FORCEPROP 1 LAST PATH I231
J 0
(-3252 2200);
DISPLAY 0.872340 (-3252 2200);
PAINT GREEN (-3252 2200);
DISPLAY INVISIBLE (-3252 2200);
FORCEADD TAP..1
(-3250 2100);
FORCEPROP 3 LASTPIN (-3300 2100) SIG_NAME M_J_CPU0_SA_CB<6>
J 0
(-3290 2110);
DISPLAY 0.659574 (-3290 2110);
PAINT MONO (-3290 2110);
DISPLAY INVISIBLE (-3290 2110);
FORCEPROP 1 LASTPIN (-3300 2100) BN 6
J 0
(-3312 2108);
DISPLAY 0.489362 (-3312 2108);
PAINT GREEN (-3312 2108);
FORCEPROP 2 LAST CDS_LIB mstr_standard
J 2
(-3250 2100);
DISPLAY 0.723404 (-3250 2100);
PAINT MONO (-3250 2100);
DISPLAY INVISIBLE (-3250 2100);
FORCEPROP 1 LAST BODY_TYPE PLUMBING
J 0
(-3250 2150);
DISPLAY 0.872340 (-3250 2150);
PAINT GREEN (-3250 2150);
DISPLAY INVISIBLE (-3250 2150);
FORCEPROP 1 LAST HDL_TAP TRUE
J 0
(-2925 1975);
DISPLAY 0.872340 (-2925 1975);
DISPLAY INVISIBLE (-2925 1975);
FORCEPROP 1 LAST PATH I232
J 0
(-3252 2100);
DISPLAY 0.872340 (-3252 2100);
PAINT GREEN (-3252 2100);
DISPLAY INVISIBLE (-3252 2100);
FORCEADD TAP..1
(-3250 2150);
FORCEPROP 3 LASTPIN (-3300 2150) SIG_NAME M_J_CPU0_SA_CB<5>
J 0
(-3290 2160);
DISPLAY 0.659574 (-3290 2160);
PAINT MONO (-3290 2160);
DISPLAY INVISIBLE (-3290 2160);
FORCEPROP 1 LASTPIN (-3300 2150) BN 5
J 0
(-3312 2158);
DISPLAY 0.489362 (-3312 2158);
PAINT GREEN (-3312 2158);
FORCEPROP 2 LAST CDS_LIB mstr_standard
J 2
(-3250 2150);
DISPLAY 0.723404 (-3250 2150);
PAINT MONO (-3250 2150);
DISPLAY INVISIBLE (-3250 2150);
FORCEPROP 1 LAST BODY_TYPE PLUMBING
J 0
(-3250 2200);
DISPLAY 0.872340 (-3250 2200);
PAINT GREEN (-3250 2200);
DISPLAY INVISIBLE (-3250 2200);
FORCEPROP 1 LAST HDL_TAP TRUE
J 0
(-2925 2025);
DISPLAY 0.872340 (-2925 2025);
DISPLAY INVISIBLE (-2925 2025);
FORCEPROP 1 LAST PATH I233
J 0
(-3252 2150);
DISPLAY 0.872340 (-3252 2150);
PAINT GREEN (-3252 2150);
DISPLAY INVISIBLE (-3252 2150);
FORCEADD TAP..1
(-3250 2050);
FORCEPROP 3 LASTPIN (-3300 2050) SIG_NAME M_J_CPU0_SA_CB<7>
J 0
(-3290 2060);
DISPLAY 0.659574 (-3290 2060);
PAINT MONO (-3290 2060);
DISPLAY INVISIBLE (-3290 2060);
FORCEPROP 1 LASTPIN (-3300 2050) BN 7
J 0
(-3312 2058);
DISPLAY 0.489362 (-3312 2058);
PAINT GREEN (-3312 2058);
FORCEPROP 2 LAST CDS_LIB mstr_standard
J 2
(-3250 2050);
DISPLAY 0.723404 (-3250 2050);
PAINT MONO (-3250 2050);
DISPLAY INVISIBLE (-3250 2050);
FORCEPROP 1 LAST BODY_TYPE PLUMBING
J 0
(-3250 2100);
DISPLAY 0.872340 (-3250 2100);
PAINT GREEN (-3250 2100);
DISPLAY INVISIBLE (-3250 2100);
FORCEPROP 1 LAST HDL_TAP TRUE
J 0
(-2925 1925);
DISPLAY 0.872340 (-2925 1925);
DISPLAY INVISIBLE (-2925 1925);
FORCEPROP 1 LAST PATH I234
J 0
(-3252 2050);
DISPLAY 0.872340 (-3252 2050);
PAINT GREEN (-3252 2050);
DISPLAY INVISIBLE (-3252 2050);
FORCEADD OFFPAGE..6
R 2
(-2650 2000);
FORCEPROP 2 LAST $XR0 95 
J 0
(-2436 2000);
DISPLAY 0.638298 (-2436 2000);
PAINT MONO (-2436 2000);
FORCEPROP 2 LAST CDS_LIB mstr_standard
J 2
(-2650 2000);
DISPLAY 0.723404 (-2650 2000);
PAINT MONO (-2650 2000);
DISPLAY INVISIBLE (-2650 2000);
FORCEPROP 1 LAST OFFPAGE TRUE
J 2
(-2975 1875);
DISPLAY 0.872340 (-2975 1875);
PAINT GREEN (-2975 1875);
DISPLAY INVISIBLE (-2975 1875);
FORCEPROP 1 LAST COMMENT_BODY TRUE
J 2
(-2750 1925);
DISPLAY 0.872340 (-2750 1925);
PAINT GREEN (-2750 1925);
DISPLAY INVISIBLE (-2750 1925);
FORCEPROP 2 LAST PATH I235
J 0
(-2425 2050);
DISPLAY 1.021277 (-2425 2050);
DISPLAY INVISIBLE (-2425 2050);
FORCEADD TAP..1
(-3250 1950);
FORCEPROP 3 LASTPIN (-3300 1950) SIG_NAME M_J_CPU0_SB_CB<0>
J 0
(-3290 1960);
DISPLAY 0.659574 (-3290 1960);
PAINT MONO (-3290 1960);
DISPLAY INVISIBLE (-3290 1960);
FORCEPROP 1 LASTPIN (-3300 1950) BN 0
J 0
(-3312 1958);
DISPLAY 0.489362 (-3312 1958);
PAINT GREEN (-3312 1958);
FORCEPROP 2 LAST CDS_LIB mstr_standard
J 2
(-3250 1950);
DISPLAY 0.723404 (-3250 1950);
PAINT MONO (-3250 1950);
DISPLAY INVISIBLE (-3250 1950);
FORCEPROP 1 LAST BODY_TYPE PLUMBING
J 0
(-3250 2000);
DISPLAY 0.872340 (-3250 2000);
PAINT GREEN (-3250 2000);
DISPLAY INVISIBLE (-3250 2000);
FORCEPROP 1 LAST HDL_TAP TRUE
J 0
(-2925 1825);
DISPLAY 0.872340 (-2925 1825);
DISPLAY INVISIBLE (-2925 1825);
FORCEPROP 1 LAST PATH I236
J 0
(-3252 1950);
DISPLAY 0.872340 (-3252 1950);
PAINT GREEN (-3252 1950);
DISPLAY INVISIBLE (-3252 1950);
FORCEADD TAP..1
(-3250 1800);
FORCEPROP 3 LASTPIN (-3300 1800) SIG_NAME M_J_CPU0_SB_CB<3>
J 0
(-3290 1810);
DISPLAY 0.659574 (-3290 1810);
PAINT MONO (-3290 1810);
DISPLAY INVISIBLE (-3290 1810);
FORCEPROP 1 LASTPIN (-3300 1800) BN 3
J 0
(-3312 1808);
DISPLAY 0.489362 (-3312 1808);
PAINT GREEN (-3312 1808);
FORCEPROP 2 LAST CDS_LIB mstr_standard
J 2
(-3250 1800);
DISPLAY 0.723404 (-3250 1800);
PAINT MONO (-3250 1800);
DISPLAY INVISIBLE (-3250 1800);
FORCEPROP 1 LAST BODY_TYPE PLUMBING
J 0
(-3250 1850);
DISPLAY 0.872340 (-3250 1850);
PAINT GREEN (-3250 1850);
DISPLAY INVISIBLE (-3250 1850);
FORCEPROP 1 LAST HDL_TAP TRUE
J 0
(-2925 1675);
DISPLAY 0.872340 (-2925 1675);
DISPLAY INVISIBLE (-2925 1675);
FORCEPROP 1 LAST PATH I237
J 0
(-3252 1800);
DISPLAY 0.872340 (-3252 1800);
PAINT GREEN (-3252 1800);
DISPLAY INVISIBLE (-3252 1800);
FORCEADD TAP..1
(-3250 1900);
FORCEPROP 3 LASTPIN (-3300 1900) SIG_NAME M_J_CPU0_SB_CB<1>
J 0
(-3290 1910);
DISPLAY 0.659574 (-3290 1910);
PAINT MONO (-3290 1910);
DISPLAY INVISIBLE (-3290 1910);
FORCEPROP 1 LASTPIN (-3300 1900) BN 1
J 0
(-3312 1908);
DISPLAY 0.489362 (-3312 1908);
PAINT GREEN (-3312 1908);
FORCEPROP 2 LAST CDS_LIB mstr_standard
J 2
(-3250 1900);
DISPLAY 0.723404 (-3250 1900);
PAINT MONO (-3250 1900);
DISPLAY INVISIBLE (-3250 1900);
FORCEPROP 1 LAST BODY_TYPE PLUMBING
J 0
(-3250 1950);
DISPLAY 0.872340 (-3250 1950);
PAINT GREEN (-3250 1950);
DISPLAY INVISIBLE (-3250 1950);
FORCEPROP 1 LAST HDL_TAP TRUE
J 0
(-2925 1775);
DISPLAY 0.872340 (-2925 1775);
DISPLAY INVISIBLE (-2925 1775);
FORCEPROP 1 LAST PATH I238
J 0
(-3252 1900);
DISPLAY 0.872340 (-3252 1900);
PAINT GREEN (-3252 1900);
DISPLAY INVISIBLE (-3252 1900);
FORCEADD TAP..1
(-3250 1850);
FORCEPROP 3 LASTPIN (-3300 1850) SIG_NAME M_J_CPU0_SB_CB<2>
J 0
(-3290 1860);
DISPLAY 0.659574 (-3290 1860);
PAINT MONO (-3290 1860);
DISPLAY INVISIBLE (-3290 1860);
FORCEPROP 1 LASTPIN (-3300 1850) BN 2
J 0
(-3312 1858);
DISPLAY 0.489362 (-3312 1858);
PAINT GREEN (-3312 1858);
FORCEPROP 2 LAST CDS_LIB mstr_standard
J 2
(-3250 1850);
DISPLAY 0.723404 (-3250 1850);
PAINT MONO (-3250 1850);
DISPLAY INVISIBLE (-3250 1850);
FORCEPROP 1 LAST BODY_TYPE PLUMBING
J 0
(-3250 1900);
DISPLAY 0.872340 (-3250 1900);
PAINT GREEN (-3250 1900);
DISPLAY INVISIBLE (-3250 1900);
FORCEPROP 1 LAST HDL_TAP TRUE
J 0
(-2925 1725);
DISPLAY 0.872340 (-2925 1725);
DISPLAY INVISIBLE (-2925 1725);
FORCEPROP 1 LAST PATH I239
J 0
(-3252 1850);
DISPLAY 0.872340 (-3252 1850);
PAINT GREEN (-3252 1850);
DISPLAY INVISIBLE (-3252 1850);
FORCEADD TAP..1
(-3250 1750);
FORCEPROP 3 LASTPIN (-3300 1750) SIG_NAME M_J_CPU0_SB_CB<4>
J 0
(-3290 1760);
DISPLAY 0.659574 (-3290 1760);
PAINT MONO (-3290 1760);
DISPLAY INVISIBLE (-3290 1760);
FORCEPROP 1 LASTPIN (-3300 1750) BN 4
J 0
(-3312 1758);
DISPLAY 0.489362 (-3312 1758);
PAINT GREEN (-3312 1758);
FORCEPROP 2 LAST CDS_LIB mstr_standard
J 2
(-3250 1750);
DISPLAY 0.723404 (-3250 1750);
PAINT MONO (-3250 1750);
DISPLAY INVISIBLE (-3250 1750);
FORCEPROP 1 LAST BODY_TYPE PLUMBING
J 0
(-3250 1800);
DISPLAY 0.872340 (-3250 1800);
PAINT GREEN (-3250 1800);
DISPLAY INVISIBLE (-3250 1800);
FORCEPROP 1 LAST HDL_TAP TRUE
J 0
(-2925 1625);
DISPLAY 0.872340 (-2925 1625);
DISPLAY INVISIBLE (-2925 1625);
FORCEPROP 1 LAST PATH I240
J 0
(-3252 1750);
DISPLAY 0.872340 (-3252 1750);
PAINT GREEN (-3252 1750);
DISPLAY INVISIBLE (-3252 1750);
FORCEADD TAP..1
(-3250 1700);
FORCEPROP 3 LASTPIN (-3300 1700) SIG_NAME M_J_CPU0_SB_CB<5>
J 0
(-3290 1710);
DISPLAY 0.659574 (-3290 1710);
PAINT MONO (-3290 1710);
DISPLAY INVISIBLE (-3290 1710);
FORCEPROP 1 LASTPIN (-3300 1700) BN 5
J 0
(-3312 1708);
DISPLAY 0.489362 (-3312 1708);
PAINT GREEN (-3312 1708);
FORCEPROP 2 LAST CDS_LIB mstr_standard
J 2
(-3250 1700);
DISPLAY 0.723404 (-3250 1700);
PAINT MONO (-3250 1700);
DISPLAY INVISIBLE (-3250 1700);
FORCEPROP 1 LAST BODY_TYPE PLUMBING
J 0
(-3250 1750);
DISPLAY 0.872340 (-3250 1750);
PAINT GREEN (-3250 1750);
DISPLAY INVISIBLE (-3250 1750);
FORCEPROP 1 LAST HDL_TAP TRUE
J 0
(-2925 1575);
DISPLAY 0.872340 (-2925 1575);
DISPLAY INVISIBLE (-2925 1575);
FORCEPROP 1 LAST PATH I241
J 0
(-3252 1700);
DISPLAY 0.872340 (-3252 1700);
PAINT GREEN (-3252 1700);
DISPLAY INVISIBLE (-3252 1700);
FORCEADD TAP..1
(-3250 1650);
FORCEPROP 3 LASTPIN (-3300 1650) SIG_NAME M_J_CPU0_SB_CB<6>
J 0
(-3290 1660);
DISPLAY 0.659574 (-3290 1660);
PAINT MONO (-3290 1660);
DISPLAY INVISIBLE (-3290 1660);
FORCEPROP 1 LASTPIN (-3300 1650) BN 6
J 0
(-3312 1658);
DISPLAY 0.489362 (-3312 1658);
PAINT GREEN (-3312 1658);
FORCEPROP 2 LAST CDS_LIB mstr_standard
J 2
(-3250 1650);
DISPLAY 0.723404 (-3250 1650);
PAINT MONO (-3250 1650);
DISPLAY INVISIBLE (-3250 1650);
FORCEPROP 1 LAST BODY_TYPE PLUMBING
J 0
(-3250 1700);
DISPLAY 0.872340 (-3250 1700);
PAINT GREEN (-3250 1700);
DISPLAY INVISIBLE (-3250 1700);
FORCEPROP 1 LAST HDL_TAP TRUE
J 0
(-2925 1525);
DISPLAY 0.872340 (-2925 1525);
DISPLAY INVISIBLE (-2925 1525);
FORCEPROP 1 LAST PATH I242
J 0
(-3252 1650);
DISPLAY 0.872340 (-3252 1650);
PAINT GREEN (-3252 1650);
DISPLAY INVISIBLE (-3252 1650);
FORCEADD TAP..1
(-3250 1600);
FORCEPROP 3 LASTPIN (-3300 1600) SIG_NAME M_J_CPU0_SB_CB<7>
J 0
(-3290 1610);
DISPLAY 0.659574 (-3290 1610);
PAINT MONO (-3290 1610);
DISPLAY INVISIBLE (-3290 1610);
FORCEPROP 1 LASTPIN (-3300 1600) BN 7
J 0
(-3312 1608);
DISPLAY 0.489362 (-3312 1608);
PAINT GREEN (-3312 1608);
FORCEPROP 2 LAST CDS_LIB mstr_standard
J 2
(-3250 1600);
DISPLAY 0.723404 (-3250 1600);
PAINT MONO (-3250 1600);
DISPLAY INVISIBLE (-3250 1600);
FORCEPROP 1 LAST BODY_TYPE PLUMBING
J 0
(-3250 1650);
DISPLAY 0.872340 (-3250 1650);
PAINT GREEN (-3250 1650);
DISPLAY INVISIBLE (-3250 1650);
FORCEPROP 1 LAST HDL_TAP TRUE
J 0
(-2925 1475);
DISPLAY 0.872340 (-2925 1475);
DISPLAY INVISIBLE (-2925 1475);
FORCEPROP 1 LAST PATH I243
J 0
(-3252 1600);
DISPLAY 0.872340 (-3252 1600);
PAINT GREEN (-3252 1600);
DISPLAY INVISIBLE (-3252 1600);
FORCEADD TAP..1
R 2
(-5675 5900);
FORCEPROP 3 LASTPIN (-5625 5900) SIG_NAME M_J_CPU0_SA_DQS_DP<1>
J 0
(-5615 5910);
DISPLAY 0.659574 (-5615 5910);
PAINT MONO (-5615 5910);
DISPLAY INVISIBLE (-5615 5910);
FORCEPROP 1 LASTPIN (-5625 5900) BN 1
J 2
(-5613 5908);
DISPLAY 0.489362 (-5613 5908);
PAINT GREEN (-5613 5908);
FORCEPROP 2 LAST CDS_LIB mstr_standard
J 2
(-5675 5900);
DISPLAY 0.723404 (-5675 5900);
PAINT MONO (-5675 5900);
DISPLAY INVISIBLE (-5675 5900);
FORCEPROP 1 LAST BODY_TYPE PLUMBING
J 2
(-5675 5950);
DISPLAY 0.872340 (-5675 5950);
PAINT GREEN (-5675 5950);
DISPLAY INVISIBLE (-5675 5950);
FORCEPROP 1 LAST HDL_TAP TRUE
J 2
(-6000 5775);
DISPLAY 0.872340 (-6000 5775);
DISPLAY INVISIBLE (-6000 5775);
FORCEPROP 1 LAST PATH I244
J 2
(-5673 5900);
DISPLAY 0.872340 (-5673 5900);
PAINT GREEN (-5673 5900);
DISPLAY INVISIBLE (-5673 5900);
FORCEADD TAP..1
R 2
(-5675 6000);
FORCEPROP 3 LASTPIN (-5625 6000) SIG_NAME M_J_CPU0_SA_DQS_DP<0>
J 0
(-5615 6010);
DISPLAY 0.659574 (-5615 6010);
PAINT MONO (-5615 6010);
DISPLAY INVISIBLE (-5615 6010);
FORCEPROP 1 LASTPIN (-5625 6000) BN 0
J 2
(-5613 6008);
DISPLAY 0.489362 (-5613 6008);
PAINT GREEN (-5613 6008);
FORCEPROP 2 LAST CDS_LIB mstr_standard
J 2
(-5675 6000);
DISPLAY 0.723404 (-5675 6000);
PAINT MONO (-5675 6000);
DISPLAY INVISIBLE (-5675 6000);
FORCEPROP 1 LAST BODY_TYPE PLUMBING
J 2
(-5675 6050);
DISPLAY 0.872340 (-5675 6050);
PAINT GREEN (-5675 6050);
DISPLAY INVISIBLE (-5675 6050);
FORCEPROP 1 LAST HDL_TAP TRUE
J 2
(-6000 5875);
DISPLAY 0.872340 (-6000 5875);
DISPLAY INVISIBLE (-6000 5875);
FORCEPROP 1 LAST PATH I245
J 2
(-5673 6000);
DISPLAY 0.872340 (-5673 6000);
PAINT GREEN (-5673 6000);
DISPLAY INVISIBLE (-5673 6000);
FORCEADD TAP..1
R 2
(-5675 5800);
FORCEPROP 3 LASTPIN (-5625 5800) SIG_NAME M_J_CPU0_SA_DQS_DP<2>
J 0
(-5615 5810);
DISPLAY 0.659574 (-5615 5810);
PAINT MONO (-5615 5810);
DISPLAY INVISIBLE (-5615 5810);
FORCEPROP 1 LASTPIN (-5625 5800) BN 2
J 2
(-5613 5808);
DISPLAY 0.489362 (-5613 5808);
PAINT GREEN (-5613 5808);
FORCEPROP 2 LAST CDS_LIB mstr_standard
J 2
(-5675 5800);
DISPLAY 0.723404 (-5675 5800);
PAINT MONO (-5675 5800);
DISPLAY INVISIBLE (-5675 5800);
FORCEPROP 1 LAST BODY_TYPE PLUMBING
J 2
(-5675 5850);
DISPLAY 0.872340 (-5675 5850);
PAINT GREEN (-5675 5850);
DISPLAY INVISIBLE (-5675 5850);
FORCEPROP 1 LAST HDL_TAP TRUE
J 2
(-6000 5675);
DISPLAY 0.872340 (-6000 5675);
DISPLAY INVISIBLE (-6000 5675);
FORCEPROP 1 LAST PATH I246
J 2
(-5673 5800);
DISPLAY 0.872340 (-5673 5800);
PAINT GREEN (-5673 5800);
DISPLAY INVISIBLE (-5673 5800);
FORCEADD TAP..1
R 2
(-5675 5700);
FORCEPROP 3 LASTPIN (-5625 5700) SIG_NAME M_J_CPU0_SA_DQS_DP<3>
J 0
(-5615 5710);
DISPLAY 0.659574 (-5615 5710);
PAINT MONO (-5615 5710);
DISPLAY INVISIBLE (-5615 5710);
FORCEPROP 1 LASTPIN (-5625 5700) BN 3
J 2
(-5613 5708);
DISPLAY 0.489362 (-5613 5708);
PAINT GREEN (-5613 5708);
FORCEPROP 2 LAST CDS_LIB mstr_standard
J 2
(-5675 5700);
DISPLAY 0.723404 (-5675 5700);
PAINT MONO (-5675 5700);
DISPLAY INVISIBLE (-5675 5700);
FORCEPROP 1 LAST BODY_TYPE PLUMBING
J 2
(-5675 5750);
DISPLAY 0.872340 (-5675 5750);
PAINT GREEN (-5675 5750);
DISPLAY INVISIBLE (-5675 5750);
FORCEPROP 1 LAST HDL_TAP TRUE
J 2
(-6000 5575);
DISPLAY 0.872340 (-6000 5575);
DISPLAY INVISIBLE (-6000 5575);
FORCEPROP 1 LAST PATH I247
J 2
(-5673 5700);
DISPLAY 0.872340 (-5673 5700);
PAINT GREEN (-5673 5700);
DISPLAY INVISIBLE (-5673 5700);
FORCEADD TAP..1
R 2
(-5875 5950);
FORCEPROP 3 LASTPIN (-5825 5950) SIG_NAME M_J_CPU0_SA_DQS_DN<0>
J 0
(-5815 5960);
DISPLAY 0.659574 (-5815 5960);
PAINT MONO (-5815 5960);
DISPLAY INVISIBLE (-5815 5960);
FORCEPROP 1 LASTPIN (-5825 5950) BN 0
J 2
(-5813 5958);
DISPLAY 0.489362 (-5813 5958);
PAINT GREEN (-5813 5958);
FORCEPROP 2 LAST CDS_LIB mstr_standard
J 2
(-5875 5950);
DISPLAY 0.723404 (-5875 5950);
PAINT MONO (-5875 5950);
DISPLAY INVISIBLE (-5875 5950);
FORCEPROP 1 LAST BODY_TYPE PLUMBING
J 2
(-5875 6000);
DISPLAY 0.872340 (-5875 6000);
PAINT GREEN (-5875 6000);
DISPLAY INVISIBLE (-5875 6000);
FORCEPROP 1 LAST HDL_TAP TRUE
J 2
(-6200 5825);
DISPLAY 0.872340 (-6200 5825);
DISPLAY INVISIBLE (-6200 5825);
FORCEPROP 1 LAST PATH I248
J 2
(-5873 5950);
DISPLAY 0.872340 (-5873 5950);
PAINT GREEN (-5873 5950);
DISPLAY INVISIBLE (-5873 5950);
FORCEADD TAP..1
R 2
(-5875 5650);
FORCEPROP 3 LASTPIN (-5825 5650) SIG_NAME M_J_CPU0_SA_DQS_DN<3>
J 0
(-5815 5660);
DISPLAY 0.659574 (-5815 5660);
PAINT MONO (-5815 5660);
DISPLAY INVISIBLE (-5815 5660);
FORCEPROP 1 LASTPIN (-5825 5650) BN 3
J 2
(-5813 5658);
DISPLAY 0.489362 (-5813 5658);
PAINT GREEN (-5813 5658);
FORCEPROP 2 LAST CDS_LIB mstr_standard
J 2
(-5875 5650);
DISPLAY 0.723404 (-5875 5650);
PAINT MONO (-5875 5650);
DISPLAY INVISIBLE (-5875 5650);
FORCEPROP 1 LAST BODY_TYPE PLUMBING
J 2
(-5875 5700);
DISPLAY 0.872340 (-5875 5700);
PAINT GREEN (-5875 5700);
DISPLAY INVISIBLE (-5875 5700);
FORCEPROP 1 LAST HDL_TAP TRUE
J 2
(-6200 5525);
DISPLAY 0.872340 (-6200 5525);
DISPLAY INVISIBLE (-6200 5525);
FORCEPROP 1 LAST PATH I249
J 2
(-5873 5650);
DISPLAY 0.872340 (-5873 5650);
PAINT GREEN (-5873 5650);
DISPLAY INVISIBLE (-5873 5650);
FORCEADD TAP..1
R 2
(-5875 5750);
FORCEPROP 3 LASTPIN (-5825 5750) SIG_NAME M_J_CPU0_SA_DQS_DN<2>
J 0
(-5815 5760);
DISPLAY 0.659574 (-5815 5760);
PAINT MONO (-5815 5760);
DISPLAY INVISIBLE (-5815 5760);
FORCEPROP 1 LASTPIN (-5825 5750) BN 2
J 2
(-5813 5758);
DISPLAY 0.489362 (-5813 5758);
PAINT GREEN (-5813 5758);
FORCEPROP 2 LAST CDS_LIB mstr_standard
J 2
(-5875 5750);
DISPLAY 0.723404 (-5875 5750);
PAINT MONO (-5875 5750);
DISPLAY INVISIBLE (-5875 5750);
FORCEPROP 1 LAST BODY_TYPE PLUMBING
J 2
(-5875 5800);
DISPLAY 0.872340 (-5875 5800);
PAINT GREEN (-5875 5800);
DISPLAY INVISIBLE (-5875 5800);
FORCEPROP 1 LAST HDL_TAP TRUE
J 2
(-6200 5625);
DISPLAY 0.872340 (-6200 5625);
DISPLAY INVISIBLE (-6200 5625);
FORCEPROP 1 LAST PATH I250
J 2
(-5873 5750);
DISPLAY 0.872340 (-5873 5750);
PAINT GREEN (-5873 5750);
DISPLAY INVISIBLE (-5873 5750);
FORCEADD TAP..1
R 2
(-5875 5850);
FORCEPROP 3 LASTPIN (-5825 5850) SIG_NAME M_J_CPU0_SA_DQS_DN<1>
J 0
(-5815 5860);
DISPLAY 0.659574 (-5815 5860);
PAINT MONO (-5815 5860);
DISPLAY INVISIBLE (-5815 5860);
FORCEPROP 1 LASTPIN (-5825 5850) BN 1
J 2
(-5813 5858);
DISPLAY 0.489362 (-5813 5858);
PAINT GREEN (-5813 5858);
FORCEPROP 2 LAST CDS_LIB mstr_standard
J 2
(-5875 5850);
DISPLAY 0.723404 (-5875 5850);
PAINT MONO (-5875 5850);
DISPLAY INVISIBLE (-5875 5850);
FORCEPROP 1 LAST BODY_TYPE PLUMBING
J 2
(-5875 5900);
DISPLAY 0.872340 (-5875 5900);
PAINT GREEN (-5875 5900);
DISPLAY INVISIBLE (-5875 5900);
FORCEPROP 1 LAST HDL_TAP TRUE
J 2
(-6200 5725);
DISPLAY 0.872340 (-6200 5725);
DISPLAY INVISIBLE (-6200 5725);
FORCEPROP 1 LAST PATH I251
J 2
(-5873 5850);
DISPLAY 0.872340 (-5873 5850);
PAINT GREEN (-5873 5850);
DISPLAY INVISIBLE (-5873 5850);
FORCEADD TAP..1
R 2
(-5675 5600);
FORCEPROP 3 LASTPIN (-5625 5600) SIG_NAME M_J_CPU0_SA_DQS_DP<4>
J 0
(-5615 5610);
DISPLAY 0.659574 (-5615 5610);
PAINT MONO (-5615 5610);
DISPLAY INVISIBLE (-5615 5610);
FORCEPROP 1 LASTPIN (-5625 5600) BN 4
J 2
(-5613 5608);
DISPLAY 0.489362 (-5613 5608);
PAINT GREEN (-5613 5608);
FORCEPROP 2 LAST CDS_LIB mstr_standard
J 2
(-5675 5600);
DISPLAY 0.723404 (-5675 5600);
PAINT MONO (-5675 5600);
DISPLAY INVISIBLE (-5675 5600);
FORCEPROP 1 LAST BODY_TYPE PLUMBING
J 2
(-5675 5650);
DISPLAY 0.872340 (-5675 5650);
PAINT GREEN (-5675 5650);
DISPLAY INVISIBLE (-5675 5650);
FORCEPROP 1 LAST HDL_TAP TRUE
J 2
(-6000 5475);
DISPLAY 0.872340 (-6000 5475);
DISPLAY INVISIBLE (-6000 5475);
FORCEPROP 1 LAST PATH I252
J 2
(-5673 5600);
DISPLAY 0.872340 (-5673 5600);
PAINT GREEN (-5673 5600);
DISPLAY INVISIBLE (-5673 5600);
FORCEADD TAP..1
R 2
(-5675 5500);
FORCEPROP 3 LASTPIN (-5625 5500) SIG_NAME M_J_CPU0_SA_DQS_DP<5>
J 0
(-5615 5510);
DISPLAY 0.659574 (-5615 5510);
PAINT MONO (-5615 5510);
DISPLAY INVISIBLE (-5615 5510);
FORCEPROP 1 LASTPIN (-5625 5500) BN 5
J 2
(-5613 5508);
DISPLAY 0.489362 (-5613 5508);
PAINT GREEN (-5613 5508);
FORCEPROP 2 LAST CDS_LIB mstr_standard
J 2
(-5675 5500);
DISPLAY 0.723404 (-5675 5500);
PAINT MONO (-5675 5500);
DISPLAY INVISIBLE (-5675 5500);
FORCEPROP 1 LAST BODY_TYPE PLUMBING
J 2
(-5675 5550);
DISPLAY 0.872340 (-5675 5550);
PAINT GREEN (-5675 5550);
DISPLAY INVISIBLE (-5675 5550);
FORCEPROP 1 LAST HDL_TAP TRUE
J 2
(-6000 5375);
DISPLAY 0.872340 (-6000 5375);
DISPLAY INVISIBLE (-6000 5375);
FORCEPROP 1 LAST PATH I253
J 2
(-5673 5500);
DISPLAY 0.872340 (-5673 5500);
PAINT GREEN (-5673 5500);
DISPLAY INVISIBLE (-5673 5500);
FORCEADD TAP..1
R 2
(-5675 5400);
FORCEPROP 3 LASTPIN (-5625 5400) SIG_NAME M_J_CPU0_SA_DQS_DP<6>
J 0
(-5615 5410);
DISPLAY 0.659574 (-5615 5410);
PAINT MONO (-5615 5410);
DISPLAY INVISIBLE (-5615 5410);
FORCEPROP 1 LASTPIN (-5625 5400) BN 6
J 2
(-5613 5408);
DISPLAY 0.489362 (-5613 5408);
PAINT GREEN (-5613 5408);
FORCEPROP 2 LAST CDS_LIB mstr_standard
J 2
(-5675 5400);
DISPLAY 0.723404 (-5675 5400);
PAINT MONO (-5675 5400);
DISPLAY INVISIBLE (-5675 5400);
FORCEPROP 1 LAST BODY_TYPE PLUMBING
J 2
(-5675 5450);
DISPLAY 0.872340 (-5675 5450);
PAINT GREEN (-5675 5450);
DISPLAY INVISIBLE (-5675 5450);
FORCEPROP 1 LAST HDL_TAP TRUE
J 2
(-6000 5275);
DISPLAY 0.872340 (-6000 5275);
DISPLAY INVISIBLE (-6000 5275);
FORCEPROP 1 LAST PATH I254
J 2
(-5673 5400);
DISPLAY 0.872340 (-5673 5400);
PAINT GREEN (-5673 5400);
DISPLAY INVISIBLE (-5673 5400);
FORCEADD TAP..1
R 2
(-5675 5300);
FORCEPROP 3 LASTPIN (-5625 5300) SIG_NAME M_J_CPU0_SA_DQS_DP<7>
J 0
(-5615 5310);
DISPLAY 0.659574 (-5615 5310);
PAINT MONO (-5615 5310);
DISPLAY INVISIBLE (-5615 5310);
FORCEPROP 1 LASTPIN (-5625 5300) BN 7
J 2
(-5613 5308);
DISPLAY 0.489362 (-5613 5308);
PAINT GREEN (-5613 5308);
FORCEPROP 2 LAST CDS_LIB mstr_standard
J 2
(-5675 5300);
DISPLAY 0.723404 (-5675 5300);
PAINT MONO (-5675 5300);
DISPLAY INVISIBLE (-5675 5300);
FORCEPROP 1 LAST BODY_TYPE PLUMBING
J 2
(-5675 5350);
DISPLAY 0.872340 (-5675 5350);
PAINT GREEN (-5675 5350);
DISPLAY INVISIBLE (-5675 5350);
FORCEPROP 1 LAST HDL_TAP TRUE
J 2
(-6000 5175);
DISPLAY 0.872340 (-6000 5175);
DISPLAY INVISIBLE (-6000 5175);
FORCEPROP 1 LAST PATH I255
J 2
(-5673 5300);
DISPLAY 0.872340 (-5673 5300);
PAINT GREEN (-5673 5300);
DISPLAY INVISIBLE (-5673 5300);
FORCEADD TAP..1
R 2
(-5675 5200);
FORCEPROP 3 LASTPIN (-5625 5200) SIG_NAME M_J_CPU0_SA_DQS_DP<8>
J 0
(-5615 5210);
DISPLAY 0.659574 (-5615 5210);
PAINT MONO (-5615 5210);
DISPLAY INVISIBLE (-5615 5210);
FORCEPROP 1 LASTPIN (-5625 5200) BN 8
J 2
(-5613 5208);
DISPLAY 0.489362 (-5613 5208);
PAINT GREEN (-5613 5208);
FORCEPROP 2 LAST CDS_LIB mstr_standard
J 2
(-5675 5200);
DISPLAY 0.723404 (-5675 5200);
PAINT MONO (-5675 5200);
DISPLAY INVISIBLE (-5675 5200);
FORCEPROP 1 LAST BODY_TYPE PLUMBING
J 2
(-5675 5250);
DISPLAY 0.872340 (-5675 5250);
PAINT GREEN (-5675 5250);
DISPLAY INVISIBLE (-5675 5250);
FORCEPROP 1 LAST HDL_TAP TRUE
J 2
(-6000 5075);
DISPLAY 0.872340 (-6000 5075);
DISPLAY INVISIBLE (-6000 5075);
FORCEPROP 1 LAST PATH I256
J 2
(-5673 5200);
DISPLAY 0.872340 (-5673 5200);
PAINT GREEN (-5673 5200);
DISPLAY INVISIBLE (-5673 5200);
FORCEADD TAP..1
R 2
(-5875 5450);
FORCEPROP 3 LASTPIN (-5825 5450) SIG_NAME M_J_CPU0_SA_DQS_DN<5>
J 0
(-5815 5460);
DISPLAY 0.659574 (-5815 5460);
PAINT MONO (-5815 5460);
DISPLAY INVISIBLE (-5815 5460);
FORCEPROP 1 LASTPIN (-5825 5450) BN 5
J 2
(-5813 5458);
DISPLAY 0.489362 (-5813 5458);
PAINT GREEN (-5813 5458);
FORCEPROP 2 LAST CDS_LIB mstr_standard
J 2
(-5875 5450);
DISPLAY 0.723404 (-5875 5450);
PAINT MONO (-5875 5450);
DISPLAY INVISIBLE (-5875 5450);
FORCEPROP 1 LAST BODY_TYPE PLUMBING
J 2
(-5875 5500);
DISPLAY 0.872340 (-5875 5500);
PAINT GREEN (-5875 5500);
DISPLAY INVISIBLE (-5875 5500);
FORCEPROP 1 LAST HDL_TAP TRUE
J 2
(-6200 5325);
DISPLAY 0.872340 (-6200 5325);
DISPLAY INVISIBLE (-6200 5325);
FORCEPROP 1 LAST PATH I257
J 2
(-5873 5450);
DISPLAY 0.872340 (-5873 5450);
PAINT GREEN (-5873 5450);
DISPLAY INVISIBLE (-5873 5450);
FORCEADD TAP..1
R 2
(-5875 5550);
FORCEPROP 3 LASTPIN (-5825 5550) SIG_NAME M_J_CPU0_SA_DQS_DN<4>
J 0
(-5815 5560);
DISPLAY 0.659574 (-5815 5560);
PAINT MONO (-5815 5560);
DISPLAY INVISIBLE (-5815 5560);
FORCEPROP 1 LASTPIN (-5825 5550) BN 4
J 2
(-5813 5558);
DISPLAY 0.489362 (-5813 5558);
PAINT GREEN (-5813 5558);
FORCEPROP 2 LAST CDS_LIB mstr_standard
J 2
(-5875 5550);
DISPLAY 0.723404 (-5875 5550);
PAINT MONO (-5875 5550);
DISPLAY INVISIBLE (-5875 5550);
FORCEPROP 1 LAST BODY_TYPE PLUMBING
J 2
(-5875 5600);
DISPLAY 0.872340 (-5875 5600);
PAINT GREEN (-5875 5600);
DISPLAY INVISIBLE (-5875 5600);
FORCEPROP 1 LAST HDL_TAP TRUE
J 2
(-6200 5425);
DISPLAY 0.872340 (-6200 5425);
DISPLAY INVISIBLE (-6200 5425);
FORCEPROP 1 LAST PATH I258
J 2
(-5873 5550);
DISPLAY 0.872340 (-5873 5550);
PAINT GREEN (-5873 5550);
DISPLAY INVISIBLE (-5873 5550);
FORCEADD TAP..1
R 2
(-5875 5150);
FORCEPROP 3 LASTPIN (-5825 5150) SIG_NAME M_J_CPU0_SA_DQS_DN<8>
J 0
(-5815 5160);
DISPLAY 0.659574 (-5815 5160);
PAINT MONO (-5815 5160);
DISPLAY INVISIBLE (-5815 5160);
FORCEPROP 1 LASTPIN (-5825 5150) BN 8
J 2
(-5813 5158);
DISPLAY 0.489362 (-5813 5158);
PAINT GREEN (-5813 5158);
FORCEPROP 2 LAST CDS_LIB mstr_standard
J 2
(-5875 5150);
DISPLAY 0.723404 (-5875 5150);
PAINT MONO (-5875 5150);
DISPLAY INVISIBLE (-5875 5150);
FORCEPROP 1 LAST BODY_TYPE PLUMBING
J 2
(-5875 5200);
DISPLAY 0.872340 (-5875 5200);
PAINT GREEN (-5875 5200);
DISPLAY INVISIBLE (-5875 5200);
FORCEPROP 1 LAST HDL_TAP TRUE
J 2
(-6200 5025);
DISPLAY 0.872340 (-6200 5025);
DISPLAY INVISIBLE (-6200 5025);
FORCEPROP 1 LAST PATH I259
J 2
(-5873 5150);
DISPLAY 0.872340 (-5873 5150);
PAINT GREEN (-5873 5150);
DISPLAY INVISIBLE (-5873 5150);
FORCEADD TAP..1
R 2
(-5875 5350);
FORCEPROP 3 LASTPIN (-5825 5350) SIG_NAME M_J_CPU0_SA_DQS_DN<6>
J 0
(-5815 5360);
DISPLAY 0.659574 (-5815 5360);
PAINT MONO (-5815 5360);
DISPLAY INVISIBLE (-5815 5360);
FORCEPROP 1 LASTPIN (-5825 5350) BN 6
J 2
(-5813 5358);
DISPLAY 0.489362 (-5813 5358);
PAINT GREEN (-5813 5358);
FORCEPROP 2 LAST CDS_LIB mstr_standard
J 2
(-5875 5350);
DISPLAY 0.723404 (-5875 5350);
PAINT MONO (-5875 5350);
DISPLAY INVISIBLE (-5875 5350);
FORCEPROP 1 LAST BODY_TYPE PLUMBING
J 2
(-5875 5400);
DISPLAY 0.872340 (-5875 5400);
PAINT GREEN (-5875 5400);
DISPLAY INVISIBLE (-5875 5400);
FORCEPROP 1 LAST HDL_TAP TRUE
J 2
(-6200 5225);
DISPLAY 0.872340 (-6200 5225);
DISPLAY INVISIBLE (-6200 5225);
FORCEPROP 1 LAST PATH I260
J 2
(-5873 5350);
DISPLAY 0.872340 (-5873 5350);
PAINT GREEN (-5873 5350);
DISPLAY INVISIBLE (-5873 5350);
FORCEADD TAP..1
R 2
(-5875 5250);
FORCEPROP 3 LASTPIN (-5825 5250) SIG_NAME M_J_CPU0_SA_DQS_DN<7>
J 0
(-5815 5260);
DISPLAY 0.659574 (-5815 5260);
PAINT MONO (-5815 5260);
DISPLAY INVISIBLE (-5815 5260);
FORCEPROP 1 LASTPIN (-5825 5250) BN 7
J 2
(-5813 5258);
DISPLAY 0.489362 (-5813 5258);
PAINT GREEN (-5813 5258);
FORCEPROP 2 LAST CDS_LIB mstr_standard
J 2
(-5875 5250);
DISPLAY 0.723404 (-5875 5250);
PAINT MONO (-5875 5250);
DISPLAY INVISIBLE (-5875 5250);
FORCEPROP 1 LAST BODY_TYPE PLUMBING
J 2
(-5875 5300);
DISPLAY 0.872340 (-5875 5300);
PAINT GREEN (-5875 5300);
DISPLAY INVISIBLE (-5875 5300);
FORCEPROP 1 LAST HDL_TAP TRUE
J 2
(-6200 5125);
DISPLAY 0.872340 (-6200 5125);
DISPLAY INVISIBLE (-6200 5125);
FORCEPROP 1 LAST PATH I261
J 2
(-5873 5250);
DISPLAY 0.872340 (-5873 5250);
PAINT GREEN (-5873 5250);
DISPLAY INVISIBLE (-5873 5250);
FORCEADD TAP..1
R 2
(-5675 4950);
FORCEPROP 3 LASTPIN (-5625 4950) SIG_NAME M_J_CPU0_SB_DQS_DP<0>
J 0
(-5615 4960);
DISPLAY 0.659574 (-5615 4960);
PAINT MONO (-5615 4960);
DISPLAY INVISIBLE (-5615 4960);
FORCEPROP 1 LASTPIN (-5625 4950) BN 0
J 2
(-5613 4958);
DISPLAY 0.489362 (-5613 4958);
PAINT GREEN (-5613 4958);
FORCEPROP 2 LAST CDS_LIB mstr_standard
J 2
(-5675 4950);
DISPLAY 0.723404 (-5675 4950);
PAINT MONO (-5675 4950);
DISPLAY INVISIBLE (-5675 4950);
FORCEPROP 1 LAST BODY_TYPE PLUMBING
J 2
(-5675 5000);
DISPLAY 0.872340 (-5675 5000);
PAINT GREEN (-5675 5000);
DISPLAY INVISIBLE (-5675 5000);
FORCEPROP 1 LAST HDL_TAP TRUE
J 2
(-6000 4825);
DISPLAY 0.872340 (-6000 4825);
DISPLAY INVISIBLE (-6000 4825);
FORCEPROP 1 LAST PATH I262
J 2
(-5673 4950);
DISPLAY 0.872340 (-5673 4950);
PAINT GREEN (-5673 4950);
DISPLAY INVISIBLE (-5673 4950);
FORCEADD TAP..1
R 2
(-5675 5100);
FORCEPROP 3 LASTPIN (-5625 5100) SIG_NAME M_J_CPU0_SA_DQS_DP<9>
J 0
(-5615 5110);
DISPLAY 0.659574 (-5615 5110);
PAINT MONO (-5615 5110);
DISPLAY INVISIBLE (-5615 5110);
FORCEPROP 1 LASTPIN (-5625 5100) BN 9
J 2
(-5613 5108);
DISPLAY 0.489362 (-5613 5108);
PAINT GREEN (-5613 5108);
FORCEPROP 2 LAST CDS_LIB mstr_standard
J 2
(-5675 5100);
DISPLAY 0.723404 (-5675 5100);
PAINT MONO (-5675 5100);
DISPLAY INVISIBLE (-5675 5100);
FORCEPROP 1 LAST BODY_TYPE PLUMBING
J 2
(-5675 5150);
DISPLAY 0.872340 (-5675 5150);
PAINT GREEN (-5675 5150);
DISPLAY INVISIBLE (-5675 5150);
FORCEPROP 1 LAST HDL_TAP TRUE
J 2
(-6000 4975);
DISPLAY 0.872340 (-6000 4975);
DISPLAY INVISIBLE (-6000 4975);
FORCEPROP 1 LAST PATH I263
J 2
(-5673 5100);
DISPLAY 0.872340 (-5673 5100);
PAINT GREEN (-5673 5100);
DISPLAY INVISIBLE (-5673 5100);
FORCEADD TAP..1
R 2
(-5675 4850);
FORCEPROP 3 LASTPIN (-5625 4850) SIG_NAME M_J_CPU0_SB_DQS_DP<1>
J 0
(-5615 4860);
DISPLAY 0.659574 (-5615 4860);
PAINT MONO (-5615 4860);
DISPLAY INVISIBLE (-5615 4860);
FORCEPROP 1 LASTPIN (-5625 4850) BN 1
J 2
(-5613 4858);
DISPLAY 0.489362 (-5613 4858);
PAINT GREEN (-5613 4858);
FORCEPROP 2 LAST CDS_LIB mstr_standard
J 2
(-5675 4850);
DISPLAY 0.723404 (-5675 4850);
PAINT MONO (-5675 4850);
DISPLAY INVISIBLE (-5675 4850);
FORCEPROP 1 LAST BODY_TYPE PLUMBING
J 2
(-5675 4900);
DISPLAY 0.872340 (-5675 4900);
PAINT GREEN (-5675 4900);
DISPLAY INVISIBLE (-5675 4900);
FORCEPROP 1 LAST HDL_TAP TRUE
J 2
(-6000 4725);
DISPLAY 0.872340 (-6000 4725);
DISPLAY INVISIBLE (-6000 4725);
FORCEPROP 1 LAST PATH I264
J 2
(-5673 4850);
DISPLAY 0.872340 (-5673 4850);
PAINT GREEN (-5673 4850);
DISPLAY INVISIBLE (-5673 4850);
FORCEADD TAP..1
R 2
(-5675 4750);
FORCEPROP 3 LASTPIN (-5625 4750) SIG_NAME M_J_CPU0_SB_DQS_DP<2>
J 0
(-5615 4760);
DISPLAY 0.659574 (-5615 4760);
PAINT MONO (-5615 4760);
DISPLAY INVISIBLE (-5615 4760);
FORCEPROP 1 LASTPIN (-5625 4750) BN 2
J 2
(-5613 4758);
DISPLAY 0.489362 (-5613 4758);
PAINT GREEN (-5613 4758);
FORCEPROP 2 LAST CDS_LIB mstr_standard
J 2
(-5675 4750);
DISPLAY 0.723404 (-5675 4750);
PAINT MONO (-5675 4750);
DISPLAY INVISIBLE (-5675 4750);
FORCEPROP 1 LAST BODY_TYPE PLUMBING
J 2
(-5675 4800);
DISPLAY 0.872340 (-5675 4800);
PAINT GREEN (-5675 4800);
DISPLAY INVISIBLE (-5675 4800);
FORCEPROP 1 LAST HDL_TAP TRUE
J 2
(-6000 4625);
DISPLAY 0.872340 (-6000 4625);
DISPLAY INVISIBLE (-6000 4625);
FORCEPROP 1 LAST PATH I265
J 2
(-5673 4750);
DISPLAY 0.872340 (-5673 4750);
PAINT GREEN (-5673 4750);
DISPLAY INVISIBLE (-5673 4750);
FORCEADD TAP..1
R 2
(-5675 4650);
FORCEPROP 3 LASTPIN (-5625 4650) SIG_NAME M_J_CPU0_SB_DQS_DP<3>
J 0
(-5615 4660);
DISPLAY 0.659574 (-5615 4660);
PAINT MONO (-5615 4660);
DISPLAY INVISIBLE (-5615 4660);
FORCEPROP 1 LASTPIN (-5625 4650) BN 3
J 2
(-5613 4658);
DISPLAY 0.489362 (-5613 4658);
PAINT GREEN (-5613 4658);
FORCEPROP 2 LAST CDS_LIB mstr_standard
J 2
(-5675 4650);
DISPLAY 0.723404 (-5675 4650);
PAINT MONO (-5675 4650);
DISPLAY INVISIBLE (-5675 4650);
FORCEPROP 1 LAST BODY_TYPE PLUMBING
J 2
(-5675 4700);
DISPLAY 0.872340 (-5675 4700);
PAINT GREEN (-5675 4700);
DISPLAY INVISIBLE (-5675 4700);
FORCEPROP 1 LAST HDL_TAP TRUE
J 2
(-6000 4525);
DISPLAY 0.872340 (-6000 4525);
DISPLAY INVISIBLE (-6000 4525);
FORCEPROP 1 LAST PATH I266
J 2
(-5673 4650);
DISPLAY 0.872340 (-5673 4650);
PAINT GREEN (-5673 4650);
DISPLAY INVISIBLE (-5673 4650);
FORCEADD TAP..1
R 2
(-5875 4900);
FORCEPROP 3 LASTPIN (-5825 4900) SIG_NAME M_J_CPU0_SB_DQS_DN<0>
J 0
(-5815 4910);
DISPLAY 0.659574 (-5815 4910);
PAINT MONO (-5815 4910);
DISPLAY INVISIBLE (-5815 4910);
FORCEPROP 1 LASTPIN (-5825 4900) BN 0
J 2
(-5813 4908);
DISPLAY 0.489362 (-5813 4908);
PAINT GREEN (-5813 4908);
FORCEPROP 2 LAST CDS_LIB mstr_standard
J 2
(-5875 4900);
DISPLAY 0.723404 (-5875 4900);
PAINT MONO (-5875 4900);
DISPLAY INVISIBLE (-5875 4900);
FORCEPROP 1 LAST BODY_TYPE PLUMBING
J 2
(-5875 4950);
DISPLAY 0.872340 (-5875 4950);
PAINT GREEN (-5875 4950);
DISPLAY INVISIBLE (-5875 4950);
FORCEPROP 1 LAST HDL_TAP TRUE
J 2
(-6200 4775);
DISPLAY 0.872340 (-6200 4775);
DISPLAY INVISIBLE (-6200 4775);
FORCEPROP 1 LAST PATH I267
J 2
(-5873 4900);
DISPLAY 0.872340 (-5873 4900);
PAINT GREEN (-5873 4900);
DISPLAY INVISIBLE (-5873 4900);
FORCEADD TAP..1
R 2
(-5875 5050);
FORCEPROP 3 LASTPIN (-5825 5050) SIG_NAME M_J_CPU0_SA_DQS_DN<9>
J 0
(-5815 5060);
DISPLAY 0.659574 (-5815 5060);
PAINT MONO (-5815 5060);
DISPLAY INVISIBLE (-5815 5060);
FORCEPROP 1 LASTPIN (-5825 5050) BN 9
J 2
(-5813 5058);
DISPLAY 0.489362 (-5813 5058);
PAINT GREEN (-5813 5058);
FORCEPROP 2 LAST CDS_LIB mstr_standard
J 2
(-5875 5050);
DISPLAY 0.723404 (-5875 5050);
PAINT MONO (-5875 5050);
DISPLAY INVISIBLE (-5875 5050);
FORCEPROP 1 LAST BODY_TYPE PLUMBING
J 2
(-5875 5100);
DISPLAY 0.872340 (-5875 5100);
PAINT GREEN (-5875 5100);
DISPLAY INVISIBLE (-5875 5100);
FORCEPROP 1 LAST HDL_TAP TRUE
J 2
(-6200 4925);
DISPLAY 0.872340 (-6200 4925);
DISPLAY INVISIBLE (-6200 4925);
FORCEPROP 1 LAST PATH I268
J 2
(-5873 5050);
DISPLAY 0.872340 (-5873 5050);
PAINT GREEN (-5873 5050);
DISPLAY INVISIBLE (-5873 5050);
FORCEADD TAP..1
R 2
(-5875 4800);
FORCEPROP 3 LASTPIN (-5825 4800) SIG_NAME M_J_CPU0_SB_DQS_DN<1>
J 0
(-5815 4810);
DISPLAY 0.659574 (-5815 4810);
PAINT MONO (-5815 4810);
DISPLAY INVISIBLE (-5815 4810);
FORCEPROP 1 LASTPIN (-5825 4800) BN 1
J 2
(-5813 4808);
DISPLAY 0.489362 (-5813 4808);
PAINT GREEN (-5813 4808);
FORCEPROP 2 LAST CDS_LIB mstr_standard
J 2
(-5875 4800);
DISPLAY 0.723404 (-5875 4800);
PAINT MONO (-5875 4800);
DISPLAY INVISIBLE (-5875 4800);
FORCEPROP 1 LAST BODY_TYPE PLUMBING
J 2
(-5875 4850);
DISPLAY 0.872340 (-5875 4850);
PAINT GREEN (-5875 4850);
DISPLAY INVISIBLE (-5875 4850);
FORCEPROP 1 LAST HDL_TAP TRUE
J 2
(-6200 4675);
DISPLAY 0.872340 (-6200 4675);
DISPLAY INVISIBLE (-6200 4675);
FORCEPROP 1 LAST PATH I269
J 2
(-5873 4800);
DISPLAY 0.872340 (-5873 4800);
PAINT GREEN (-5873 4800);
DISPLAY INVISIBLE (-5873 4800);
FORCEADD TAP..1
R 2
(-5875 4700);
FORCEPROP 3 LASTPIN (-5825 4700) SIG_NAME M_J_CPU0_SB_DQS_DN<2>
J 0
(-5815 4710);
DISPLAY 0.659574 (-5815 4710);
PAINT MONO (-5815 4710);
DISPLAY INVISIBLE (-5815 4710);
FORCEPROP 1 LASTPIN (-5825 4700) BN 2
J 2
(-5813 4708);
DISPLAY 0.489362 (-5813 4708);
PAINT GREEN (-5813 4708);
FORCEPROP 2 LAST CDS_LIB mstr_standard
J 2
(-5875 4700);
DISPLAY 0.723404 (-5875 4700);
PAINT MONO (-5875 4700);
DISPLAY INVISIBLE (-5875 4700);
FORCEPROP 1 LAST BODY_TYPE PLUMBING
J 2
(-5875 4750);
DISPLAY 0.872340 (-5875 4750);
PAINT GREEN (-5875 4750);
DISPLAY INVISIBLE (-5875 4750);
FORCEPROP 1 LAST HDL_TAP TRUE
J 2
(-6200 4575);
DISPLAY 0.872340 (-6200 4575);
DISPLAY INVISIBLE (-6200 4575);
FORCEPROP 1 LAST PATH I270
J 2
(-5873 4700);
DISPLAY 0.872340 (-5873 4700);
PAINT GREEN (-5873 4700);
DISPLAY INVISIBLE (-5873 4700);
FORCEADD TAP..1
R 2
(-5675 4550);
FORCEPROP 3 LASTPIN (-5625 4550) SIG_NAME M_J_CPU0_SB_DQS_DP<4>
J 0
(-5615 4560);
DISPLAY 0.659574 (-5615 4560);
PAINT MONO (-5615 4560);
DISPLAY INVISIBLE (-5615 4560);
FORCEPROP 1 LASTPIN (-5625 4550) BN 4
J 2
(-5613 4558);
DISPLAY 0.489362 (-5613 4558);
PAINT GREEN (-5613 4558);
FORCEPROP 2 LAST CDS_LIB mstr_standard
J 2
(-5675 4550);
DISPLAY 0.723404 (-5675 4550);
PAINT MONO (-5675 4550);
DISPLAY INVISIBLE (-5675 4550);
FORCEPROP 1 LAST BODY_TYPE PLUMBING
J 2
(-5675 4600);
DISPLAY 0.872340 (-5675 4600);
PAINT GREEN (-5675 4600);
DISPLAY INVISIBLE (-5675 4600);
FORCEPROP 1 LAST HDL_TAP TRUE
J 2
(-6000 4425);
DISPLAY 0.872340 (-6000 4425);
DISPLAY INVISIBLE (-6000 4425);
FORCEPROP 1 LAST PATH I271
J 2
(-5673 4550);
DISPLAY 0.872340 (-5673 4550);
PAINT GREEN (-5673 4550);
DISPLAY INVISIBLE (-5673 4550);
FORCEADD TAP..1
R 2
(-5675 4450);
FORCEPROP 3 LASTPIN (-5625 4450) SIG_NAME M_J_CPU0_SB_DQS_DP<5>
J 0
(-5615 4460);
DISPLAY 0.659574 (-5615 4460);
PAINT MONO (-5615 4460);
DISPLAY INVISIBLE (-5615 4460);
FORCEPROP 1 LASTPIN (-5625 4450) BN 5
J 2
(-5613 4458);
DISPLAY 0.489362 (-5613 4458);
PAINT GREEN (-5613 4458);
FORCEPROP 2 LAST CDS_LIB mstr_standard
J 2
(-5675 4450);
DISPLAY 0.723404 (-5675 4450);
PAINT MONO (-5675 4450);
DISPLAY INVISIBLE (-5675 4450);
FORCEPROP 1 LAST BODY_TYPE PLUMBING
J 2
(-5675 4500);
DISPLAY 0.872340 (-5675 4500);
PAINT GREEN (-5675 4500);
DISPLAY INVISIBLE (-5675 4500);
FORCEPROP 1 LAST HDL_TAP TRUE
J 2
(-6000 4325);
DISPLAY 0.872340 (-6000 4325);
DISPLAY INVISIBLE (-6000 4325);
FORCEPROP 1 LAST PATH I272
J 2
(-5673 4450);
DISPLAY 0.872340 (-5673 4450);
PAINT GREEN (-5673 4450);
DISPLAY INVISIBLE (-5673 4450);
FORCEADD TAP..1
R 2
(-5875 4600);
FORCEPROP 3 LASTPIN (-5825 4600) SIG_NAME M_J_CPU0_SB_DQS_DN<3>
J 0
(-5815 4610);
DISPLAY 0.659574 (-5815 4610);
PAINT MONO (-5815 4610);
DISPLAY INVISIBLE (-5815 4610);
FORCEPROP 1 LASTPIN (-5825 4600) BN 3
J 2
(-5813 4608);
DISPLAY 0.489362 (-5813 4608);
PAINT GREEN (-5813 4608);
FORCEPROP 2 LAST CDS_LIB mstr_standard
J 2
(-5875 4600);
DISPLAY 0.723404 (-5875 4600);
PAINT MONO (-5875 4600);
DISPLAY INVISIBLE (-5875 4600);
FORCEPROP 1 LAST BODY_TYPE PLUMBING
J 2
(-5875 4650);
DISPLAY 0.872340 (-5875 4650);
PAINT GREEN (-5875 4650);
DISPLAY INVISIBLE (-5875 4650);
FORCEPROP 1 LAST HDL_TAP TRUE
J 2
(-6200 4475);
DISPLAY 0.872340 (-6200 4475);
DISPLAY INVISIBLE (-6200 4475);
FORCEPROP 1 LAST PATH I273
J 2
(-5873 4600);
DISPLAY 0.872340 (-5873 4600);
PAINT GREEN (-5873 4600);
DISPLAY INVISIBLE (-5873 4600);
FORCEADD TAP..1
R 2
(-5675 4350);
FORCEPROP 3 LASTPIN (-5625 4350) SIG_NAME M_J_CPU0_SB_DQS_DP<6>
J 0
(-5615 4360);
DISPLAY 0.659574 (-5615 4360);
PAINT MONO (-5615 4360);
DISPLAY INVISIBLE (-5615 4360);
FORCEPROP 1 LASTPIN (-5625 4350) BN 6
J 2
(-5613 4358);
DISPLAY 0.489362 (-5613 4358);
PAINT GREEN (-5613 4358);
FORCEPROP 2 LAST CDS_LIB mstr_standard
J 2
(-5675 4350);
DISPLAY 0.723404 (-5675 4350);
PAINT MONO (-5675 4350);
DISPLAY INVISIBLE (-5675 4350);
FORCEPROP 1 LAST BODY_TYPE PLUMBING
J 2
(-5675 4400);
DISPLAY 0.872340 (-5675 4400);
PAINT GREEN (-5675 4400);
DISPLAY INVISIBLE (-5675 4400);
FORCEPROP 1 LAST HDL_TAP TRUE
J 2
(-6000 4225);
DISPLAY 0.872340 (-6000 4225);
DISPLAY INVISIBLE (-6000 4225);
FORCEPROP 1 LAST PATH I274
J 2
(-5673 4350);
DISPLAY 0.872340 (-5673 4350);
PAINT GREEN (-5673 4350);
DISPLAY INVISIBLE (-5673 4350);
FORCEADD TAP..1
R 2
(-5675 4250);
FORCEPROP 3 LASTPIN (-5625 4250) SIG_NAME M_J_CPU0_SB_DQS_DP<7>
J 0
(-5615 4260);
DISPLAY 0.659574 (-5615 4260);
PAINT MONO (-5615 4260);
DISPLAY INVISIBLE (-5615 4260);
FORCEPROP 1 LASTPIN (-5625 4250) BN 7
J 2
(-5613 4258);
DISPLAY 0.489362 (-5613 4258);
PAINT GREEN (-5613 4258);
FORCEPROP 2 LAST CDS_LIB mstr_standard
J 2
(-5675 4250);
DISPLAY 0.723404 (-5675 4250);
PAINT MONO (-5675 4250);
DISPLAY INVISIBLE (-5675 4250);
FORCEPROP 1 LAST BODY_TYPE PLUMBING
J 2
(-5675 4300);
DISPLAY 0.872340 (-5675 4300);
PAINT GREEN (-5675 4300);
DISPLAY INVISIBLE (-5675 4300);
FORCEPROP 1 LAST HDL_TAP TRUE
J 2
(-6000 4125);
DISPLAY 0.872340 (-6000 4125);
DISPLAY INVISIBLE (-6000 4125);
FORCEPROP 1 LAST PATH I275
J 2
(-5673 4250);
DISPLAY 0.872340 (-5673 4250);
PAINT GREEN (-5673 4250);
DISPLAY INVISIBLE (-5673 4250);
FORCEADD TAP..1
R 2
(-5675 4150);
FORCEPROP 3 LASTPIN (-5625 4150) SIG_NAME M_J_CPU0_SB_DQS_DP<8>
J 0
(-5615 4160);
DISPLAY 0.659574 (-5615 4160);
PAINT MONO (-5615 4160);
DISPLAY INVISIBLE (-5615 4160);
FORCEPROP 1 LASTPIN (-5625 4150) BN 8
J 2
(-5613 4158);
DISPLAY 0.489362 (-5613 4158);
PAINT GREEN (-5613 4158);
FORCEPROP 2 LAST CDS_LIB mstr_standard
J 2
(-5675 4150);
DISPLAY 0.723404 (-5675 4150);
PAINT MONO (-5675 4150);
DISPLAY INVISIBLE (-5675 4150);
FORCEPROP 1 LAST BODY_TYPE PLUMBING
J 2
(-5675 4200);
DISPLAY 0.872340 (-5675 4200);
PAINT GREEN (-5675 4200);
DISPLAY INVISIBLE (-5675 4200);
FORCEPROP 1 LAST HDL_TAP TRUE
J 2
(-6000 4025);
DISPLAY 0.872340 (-6000 4025);
DISPLAY INVISIBLE (-6000 4025);
FORCEPROP 1 LAST PATH I276
J 2
(-5673 4150);
DISPLAY 0.872340 (-5673 4150);
PAINT GREEN (-5673 4150);
DISPLAY INVISIBLE (-5673 4150);
FORCEADD TAP..1
R 2
(-5875 4400);
FORCEPROP 3 LASTPIN (-5825 4400) SIG_NAME M_J_CPU0_SB_DQS_DN<5>
J 0
(-5815 4410);
DISPLAY 0.659574 (-5815 4410);
PAINT MONO (-5815 4410);
DISPLAY INVISIBLE (-5815 4410);
FORCEPROP 1 LASTPIN (-5825 4400) BN 5
J 2
(-5813 4408);
DISPLAY 0.489362 (-5813 4408);
PAINT GREEN (-5813 4408);
FORCEPROP 2 LAST CDS_LIB mstr_standard
J 2
(-5875 4400);
DISPLAY 0.723404 (-5875 4400);
PAINT MONO (-5875 4400);
DISPLAY INVISIBLE (-5875 4400);
FORCEPROP 1 LAST BODY_TYPE PLUMBING
J 2
(-5875 4450);
DISPLAY 0.872340 (-5875 4450);
PAINT GREEN (-5875 4450);
DISPLAY INVISIBLE (-5875 4450);
FORCEPROP 1 LAST HDL_TAP TRUE
J 2
(-6200 4275);
DISPLAY 0.872340 (-6200 4275);
DISPLAY INVISIBLE (-6200 4275);
FORCEPROP 1 LAST PATH I277
J 2
(-5873 4400);
DISPLAY 0.872340 (-5873 4400);
PAINT GREEN (-5873 4400);
DISPLAY INVISIBLE (-5873 4400);
FORCEADD TAP..1
R 2
(-5875 4500);
FORCEPROP 3 LASTPIN (-5825 4500) SIG_NAME M_J_CPU0_SB_DQS_DN<4>
J 0
(-5815 4510);
DISPLAY 0.659574 (-5815 4510);
PAINT MONO (-5815 4510);
DISPLAY INVISIBLE (-5815 4510);
FORCEPROP 1 LASTPIN (-5825 4500) BN 4
J 2
(-5813 4508);
DISPLAY 0.489362 (-5813 4508);
PAINT GREEN (-5813 4508);
FORCEPROP 2 LAST CDS_LIB mstr_standard
J 2
(-5875 4500);
DISPLAY 0.723404 (-5875 4500);
PAINT MONO (-5875 4500);
DISPLAY INVISIBLE (-5875 4500);
FORCEPROP 1 LAST BODY_TYPE PLUMBING
J 2
(-5875 4550);
DISPLAY 0.872340 (-5875 4550);
PAINT GREEN (-5875 4550);
DISPLAY INVISIBLE (-5875 4550);
FORCEPROP 1 LAST HDL_TAP TRUE
J 2
(-6200 4375);
DISPLAY 0.872340 (-6200 4375);
DISPLAY INVISIBLE (-6200 4375);
FORCEPROP 1 LAST PATH I278
J 2
(-5873 4500);
DISPLAY 0.872340 (-5873 4500);
PAINT GREEN (-5873 4500);
DISPLAY INVISIBLE (-5873 4500);
FORCEADD TAP..1
R 2
(-5875 4100);
FORCEPROP 3 LASTPIN (-5825 4100) SIG_NAME M_J_CPU0_SB_DQS_DN<8>
J 0
(-5815 4110);
DISPLAY 0.659574 (-5815 4110);
PAINT MONO (-5815 4110);
DISPLAY INVISIBLE (-5815 4110);
FORCEPROP 1 LASTPIN (-5825 4100) BN 8
J 2
(-5813 4108);
DISPLAY 0.489362 (-5813 4108);
PAINT GREEN (-5813 4108);
FORCEPROP 2 LAST CDS_LIB mstr_standard
J 2
(-5875 4100);
DISPLAY 0.723404 (-5875 4100);
PAINT MONO (-5875 4100);
DISPLAY INVISIBLE (-5875 4100);
FORCEPROP 1 LAST BODY_TYPE PLUMBING
J 2
(-5875 4150);
DISPLAY 0.872340 (-5875 4150);
PAINT GREEN (-5875 4150);
DISPLAY INVISIBLE (-5875 4150);
FORCEPROP 1 LAST HDL_TAP TRUE
J 2
(-6200 3975);
DISPLAY 0.872340 (-6200 3975);
DISPLAY INVISIBLE (-6200 3975);
FORCEPROP 1 LAST PATH I279
J 2
(-5873 4100);
DISPLAY 0.872340 (-5873 4100);
PAINT GREEN (-5873 4100);
DISPLAY INVISIBLE (-5873 4100);
FORCEADD TAP..1
R 2
(-5875 4200);
FORCEPROP 3 LASTPIN (-5825 4200) SIG_NAME M_J_CPU0_SB_DQS_DN<7>
J 0
(-5815 4210);
DISPLAY 0.659574 (-5815 4210);
PAINT MONO (-5815 4210);
DISPLAY INVISIBLE (-5815 4210);
FORCEPROP 1 LASTPIN (-5825 4200) BN 7
J 2
(-5813 4208);
DISPLAY 0.489362 (-5813 4208);
PAINT GREEN (-5813 4208);
FORCEPROP 2 LAST CDS_LIB mstr_standard
J 2
(-5875 4200);
DISPLAY 0.723404 (-5875 4200);
PAINT MONO (-5875 4200);
DISPLAY INVISIBLE (-5875 4200);
FORCEPROP 1 LAST BODY_TYPE PLUMBING
J 2
(-5875 4250);
DISPLAY 0.872340 (-5875 4250);
PAINT GREEN (-5875 4250);
DISPLAY INVISIBLE (-5875 4250);
FORCEPROP 1 LAST HDL_TAP TRUE
J 2
(-6200 4075);
DISPLAY 0.872340 (-6200 4075);
DISPLAY INVISIBLE (-6200 4075);
FORCEPROP 1 LAST PATH I280
J 2
(-5873 4200);
DISPLAY 0.872340 (-5873 4200);
PAINT GREEN (-5873 4200);
DISPLAY INVISIBLE (-5873 4200);
FORCEADD TAP..1
R 2
(-5875 4300);
FORCEPROP 3 LASTPIN (-5825 4300) SIG_NAME M_J_CPU0_SB_DQS_DN<6>
J 0
(-5815 4310);
DISPLAY 0.659574 (-5815 4310);
PAINT MONO (-5815 4310);
DISPLAY INVISIBLE (-5815 4310);
FORCEPROP 1 LASTPIN (-5825 4300) BN 6
J 2
(-5813 4308);
DISPLAY 0.489362 (-5813 4308);
PAINT GREEN (-5813 4308);
FORCEPROP 2 LAST CDS_LIB mstr_standard
J 2
(-5875 4300);
DISPLAY 0.723404 (-5875 4300);
PAINT MONO (-5875 4300);
DISPLAY INVISIBLE (-5875 4300);
FORCEPROP 1 LAST BODY_TYPE PLUMBING
J 2
(-5875 4350);
DISPLAY 0.872340 (-5875 4350);
PAINT GREEN (-5875 4350);
DISPLAY INVISIBLE (-5875 4350);
FORCEPROP 1 LAST HDL_TAP TRUE
J 2
(-6200 4175);
DISPLAY 0.872340 (-6200 4175);
DISPLAY INVISIBLE (-6200 4175);
FORCEPROP 1 LAST PATH I281
J 2
(-5873 4300);
DISPLAY 0.872340 (-5873 4300);
PAINT GREEN (-5873 4300);
DISPLAY INVISIBLE (-5873 4300);
FORCEADD OFFPAGE..3
R 2
(-6575 6025);
FORCEPROP 2 LAST $XR0 95 
J 0
(-6854 6025);
DISPLAY 0.638298 (-6854 6025);
PAINT MONO (-6854 6025);
FORCEPROP 2 LAST CDS_LIB standard
J 0
(-6575 6025);
DISPLAY INVISIBLE (-6575 6025);
FORCEPROP 1 LAST OFFPAGE TRUE
J 2
(-6900 5900);
DISPLAY 0.872340 (-6900 5900);
PAINT GREEN (-6900 5900);
DISPLAY INVISIBLE (-6900 5900);
FORCEPROP 1 LAST COMMENT_BODY TRUE
J 2
(-6525 5925);
DISPLAY 0.872340 (-6525 5925);
PAINT GREEN (-6525 5925);
DISPLAY INVISIBLE (-6525 5925);
FORCEPROP 2 LAST PATH I282
J 0
(-6875 6075);
DISPLAY 1.021277 (-6875 6075);
DISPLAY INVISIBLE (-6875 6075);
FORCEADD OFFPAGE..3
R 2
(-6575 5975);
FORCEPROP 2 LAST $XR0 95 
J 0
(-6854 5975);
DISPLAY 0.638298 (-6854 5975);
PAINT MONO (-6854 5975);
FORCEPROP 2 LAST CDS_LIB standard
J 0
(-6575 5975);
DISPLAY INVISIBLE (-6575 5975);
FORCEPROP 1 LAST OFFPAGE TRUE
J 2
(-6900 5850);
DISPLAY 0.872340 (-6900 5850);
PAINT GREEN (-6900 5850);
DISPLAY INVISIBLE (-6900 5850);
FORCEPROP 1 LAST COMMENT_BODY TRUE
J 2
(-6525 5875);
DISPLAY 0.872340 (-6525 5875);
PAINT GREEN (-6525 5875);
DISPLAY INVISIBLE (-6525 5875);
FORCEPROP 2 LAST PATH I283
J 0
(-6875 6025);
DISPLAY 1.021277 (-6875 6025);
DISPLAY INVISIBLE (-6875 6025);
FORCEADD OFFPAGE..3
R 2
(-6575 4975);
FORCEPROP 2 LAST $XR0 95 
J 0
(-6854 4975);
DISPLAY 0.638298 (-6854 4975);
PAINT MONO (-6854 4975);
FORCEPROP 2 LAST CDS_LIB standard
J 0
(-6575 4975);
DISPLAY INVISIBLE (-6575 4975);
FORCEPROP 1 LAST OFFPAGE TRUE
J 2
(-6900 4850);
DISPLAY 0.872340 (-6900 4850);
PAINT GREEN (-6900 4850);
DISPLAY INVISIBLE (-6900 4850);
FORCEPROP 1 LAST COMMENT_BODY TRUE
J 2
(-6525 4875);
DISPLAY 0.872340 (-6525 4875);
PAINT GREEN (-6525 4875);
DISPLAY INVISIBLE (-6525 4875);
FORCEPROP 2 LAST PATH I284
J 0
(-6875 5025);
DISPLAY 1.021277 (-6875 5025);
DISPLAY INVISIBLE (-6875 5025);
FORCEADD OFFPAGE..3
R 2
(-6575 4925);
FORCEPROP 2 LAST $XR0 95 
J 0
(-6854 4925);
DISPLAY 0.638298 (-6854 4925);
PAINT MONO (-6854 4925);
FORCEPROP 2 LAST CDS_LIB standard
J 0
(-6575 4925);
DISPLAY INVISIBLE (-6575 4925);
FORCEPROP 1 LAST OFFPAGE TRUE
J 2
(-6900 4800);
DISPLAY 0.872340 (-6900 4800);
PAINT GREEN (-6900 4800);
DISPLAY INVISIBLE (-6900 4800);
FORCEPROP 1 LAST COMMENT_BODY TRUE
J 2
(-6525 4825);
DISPLAY 0.872340 (-6525 4825);
PAINT GREEN (-6525 4825);
DISPLAY INVISIBLE (-6525 4825);
FORCEPROP 2 LAST PATH I285
J 0
(-6875 4975);
DISPLAY 1.021277 (-6875 4975);
DISPLAY INVISIBLE (-6875 4975);
FORCEADD TAP..1
R 2
(-5675 4050);
FORCEPROP 3 LASTPIN (-5625 4050) SIG_NAME M_J_CPU0_SB_DQS_DP<9>
J 0
(-5615 4060);
DISPLAY 0.659574 (-5615 4060);
PAINT MONO (-5615 4060);
DISPLAY INVISIBLE (-5615 4060);
FORCEPROP 1 LASTPIN (-5625 4050) BN 9
J 2
(-5613 4058);
DISPLAY 0.489362 (-5613 4058);
PAINT GREEN (-5613 4058);
FORCEPROP 2 LAST CDS_LIB mstr_standard
J 2
(-5675 4050);
DISPLAY 0.723404 (-5675 4050);
PAINT MONO (-5675 4050);
DISPLAY INVISIBLE (-5675 4050);
FORCEPROP 1 LAST BODY_TYPE PLUMBING
J 2
(-5675 4100);
DISPLAY 0.872340 (-5675 4100);
PAINT GREEN (-5675 4100);
DISPLAY INVISIBLE (-5675 4100);
FORCEPROP 1 LAST HDL_TAP TRUE
J 2
(-6000 3925);
DISPLAY 0.872340 (-6000 3925);
DISPLAY INVISIBLE (-6000 3925);
FORCEPROP 1 LAST PATH I286
J 2
(-5673 4050);
DISPLAY 0.872340 (-5673 4050);
PAINT GREEN (-5673 4050);
DISPLAY INVISIBLE (-5673 4050);
FORCEADD TAP..1
R 2
(-5875 3850);
FORCEPROP 3 LASTPIN (-5825 3850) SIG_NAME M_J_CPU0_SA_CA<0>
J 0
(-5815 3860);
DISPLAY 0.659574 (-5815 3860);
PAINT MONO (-5815 3860);
DISPLAY INVISIBLE (-5815 3860);
FORCEPROP 1 LASTPIN (-5825 3850) BN 0
J 2
(-5813 3858);
DISPLAY 0.489362 (-5813 3858);
PAINT GREEN (-5813 3858);
FORCEPROP 2 LAST CDS_LIB mstr_standard
J 0
(-5875 3850);
DISPLAY 0.723404 (-5875 3850);
PAINT MONO (-5875 3850);
DISPLAY INVISIBLE (-5875 3850);
FORCEPROP 1 LAST BODY_TYPE PLUMBING
J 2
(-5875 3900);
DISPLAY 0.872340 (-5875 3900);
PAINT GREEN (-5875 3900);
DISPLAY INVISIBLE (-5875 3900);
FORCEPROP 1 LAST HDL_TAP TRUE
J 2
(-6200 3725);
DISPLAY 0.872340 (-6200 3725);
DISPLAY INVISIBLE (-6200 3725);
FORCEPROP 1 LAST PATH I287
J 2
(-5873 3850);
DISPLAY 0.872340 (-5873 3850);
PAINT GREEN (-5873 3850);
DISPLAY INVISIBLE (-5873 3850);
FORCEADD TAP..1
R 2
(-5875 4000);
FORCEPROP 3 LASTPIN (-5825 4000) SIG_NAME M_J_CPU0_SB_DQS_DN<9>
J 0
(-5815 4010);
DISPLAY 0.659574 (-5815 4010);
PAINT MONO (-5815 4010);
DISPLAY INVISIBLE (-5815 4010);
FORCEPROP 1 LASTPIN (-5825 4000) BN 9
J 2
(-5813 4008);
DISPLAY 0.489362 (-5813 4008);
PAINT GREEN (-5813 4008);
FORCEPROP 2 LAST CDS_LIB mstr_standard
J 2
(-5875 4000);
DISPLAY 0.723404 (-5875 4000);
PAINT MONO (-5875 4000);
DISPLAY INVISIBLE (-5875 4000);
FORCEPROP 1 LAST BODY_TYPE PLUMBING
J 2
(-5875 4050);
DISPLAY 0.872340 (-5875 4050);
PAINT GREEN (-5875 4050);
DISPLAY INVISIBLE (-5875 4050);
FORCEPROP 1 LAST HDL_TAP TRUE
J 2
(-6200 3875);
DISPLAY 0.872340 (-6200 3875);
DISPLAY INVISIBLE (-6200 3875);
FORCEPROP 1 LAST PATH I288
J 2
(-5873 4000);
DISPLAY 0.872340 (-5873 4000);
PAINT GREEN (-5873 4000);
DISPLAY INVISIBLE (-5873 4000);
FORCEADD TAP..1
R 2
(-5875 3700);
FORCEPROP 3 LASTPIN (-5825 3700) SIG_NAME M_J_CPU0_SA_CA<3>
J 0
(-5815 3710);
DISPLAY 0.659574 (-5815 3710);
PAINT MONO (-5815 3710);
DISPLAY INVISIBLE (-5815 3710);
FORCEPROP 1 LASTPIN (-5825 3700) BN 3
J 2
(-5813 3708);
DISPLAY 0.489362 (-5813 3708);
PAINT GREEN (-5813 3708);
FORCEPROP 2 LAST CDS_LIB mstr_standard
J 0
(-5875 3700);
DISPLAY 0.723404 (-5875 3700);
PAINT MONO (-5875 3700);
DISPLAY INVISIBLE (-5875 3700);
FORCEPROP 1 LAST BODY_TYPE PLUMBING
J 2
(-5875 3750);
DISPLAY 0.872340 (-5875 3750);
PAINT GREEN (-5875 3750);
DISPLAY INVISIBLE (-5875 3750);
FORCEPROP 1 LAST HDL_TAP TRUE
J 2
(-6200 3575);
DISPLAY 0.872340 (-6200 3575);
DISPLAY INVISIBLE (-6200 3575);
FORCEPROP 1 LAST PATH I289
J 2
(-5873 3700);
DISPLAY 0.872340 (-5873 3700);
PAINT GREEN (-5873 3700);
DISPLAY INVISIBLE (-5873 3700);
FORCEADD TAP..1
R 2
(-5875 3750);
FORCEPROP 3 LASTPIN (-5825 3750) SIG_NAME M_J_CPU0_SA_CA<2>
J 0
(-5815 3760);
DISPLAY 0.659574 (-5815 3760);
PAINT MONO (-5815 3760);
DISPLAY INVISIBLE (-5815 3760);
FORCEPROP 1 LASTPIN (-5825 3750) BN 2
J 2
(-5813 3758);
DISPLAY 0.489362 (-5813 3758);
PAINT GREEN (-5813 3758);
FORCEPROP 2 LAST CDS_LIB mstr_standard
J 0
(-5875 3750);
DISPLAY 0.723404 (-5875 3750);
PAINT MONO (-5875 3750);
DISPLAY INVISIBLE (-5875 3750);
FORCEPROP 1 LAST BODY_TYPE PLUMBING
J 2
(-5875 3800);
DISPLAY 0.872340 (-5875 3800);
PAINT GREEN (-5875 3800);
DISPLAY INVISIBLE (-5875 3800);
FORCEPROP 1 LAST HDL_TAP TRUE
J 2
(-6200 3625);
DISPLAY 0.872340 (-6200 3625);
DISPLAY INVISIBLE (-6200 3625);
FORCEPROP 1 LAST PATH I290
J 2
(-5873 3750);
DISPLAY 0.872340 (-5873 3750);
PAINT GREEN (-5873 3750);
DISPLAY INVISIBLE (-5873 3750);
FORCEADD TAP..1
R 2
(-5875 3800);
FORCEPROP 3 LASTPIN (-5825 3800) SIG_NAME M_J_CPU0_SA_CA<1>
J 0
(-5815 3810);
DISPLAY 0.659574 (-5815 3810);
PAINT MONO (-5815 3810);
DISPLAY INVISIBLE (-5815 3810);
FORCEPROP 1 LASTPIN (-5825 3800) BN 1
J 2
(-5813 3808);
DISPLAY 0.489362 (-5813 3808);
PAINT GREEN (-5813 3808);
FORCEPROP 2 LAST CDS_LIB mstr_standard
J 0
(-5875 3800);
DISPLAY 0.723404 (-5875 3800);
PAINT MONO (-5875 3800);
DISPLAY INVISIBLE (-5875 3800);
FORCEPROP 1 LAST BODY_TYPE PLUMBING
J 2
(-5875 3850);
DISPLAY 0.872340 (-5875 3850);
PAINT GREEN (-5875 3850);
DISPLAY INVISIBLE (-5875 3850);
FORCEPROP 1 LAST HDL_TAP TRUE
J 2
(-6200 3675);
DISPLAY 0.872340 (-6200 3675);
DISPLAY INVISIBLE (-6200 3675);
FORCEPROP 1 LAST PATH I291
J 2
(-5873 3800);
DISPLAY 0.872340 (-5873 3800);
PAINT GREEN (-5873 3800);
DISPLAY INVISIBLE (-5873 3800);
FORCEADD TAP..1
R 2
(-5875 3650);
FORCEPROP 3 LASTPIN (-5825 3650) SIG_NAME M_J_CPU0_SA_CA<4>
J 0
(-5815 3660);
DISPLAY 0.659574 (-5815 3660);
PAINT MONO (-5815 3660);
DISPLAY INVISIBLE (-5815 3660);
FORCEPROP 1 LASTPIN (-5825 3650) BN 4
J 2
(-5813 3658);
DISPLAY 0.489362 (-5813 3658);
PAINT GREEN (-5813 3658);
FORCEPROP 2 LAST CDS_LIB mstr_standard
J 0
(-5875 3650);
DISPLAY 0.723404 (-5875 3650);
PAINT MONO (-5875 3650);
DISPLAY INVISIBLE (-5875 3650);
FORCEPROP 1 LAST BODY_TYPE PLUMBING
J 2
(-5875 3700);
DISPLAY 0.872340 (-5875 3700);
PAINT GREEN (-5875 3700);
DISPLAY INVISIBLE (-5875 3700);
FORCEPROP 1 LAST HDL_TAP TRUE
J 2
(-6200 3525);
DISPLAY 0.872340 (-6200 3525);
DISPLAY INVISIBLE (-6200 3525);
FORCEPROP 1 LAST PATH I292
J 2
(-5873 3650);
DISPLAY 0.872340 (-5873 3650);
PAINT GREEN (-5873 3650);
DISPLAY INVISIBLE (-5873 3650);
FORCEADD TAP..1
R 2
(-5875 3600);
FORCEPROP 3 LASTPIN (-5825 3600) SIG_NAME M_J_CPU0_SA_CA<5>
J 0
(-5815 3610);
DISPLAY 0.659574 (-5815 3610);
PAINT MONO (-5815 3610);
DISPLAY INVISIBLE (-5815 3610);
FORCEPROP 1 LASTPIN (-5825 3600) BN 5
J 2
(-5813 3608);
DISPLAY 0.489362 (-5813 3608);
PAINT GREEN (-5813 3608);
FORCEPROP 2 LAST CDS_LIB mstr_standard
J 0
(-5875 3600);
DISPLAY 0.723404 (-5875 3600);
PAINT MONO (-5875 3600);
DISPLAY INVISIBLE (-5875 3600);
FORCEPROP 1 LAST BODY_TYPE PLUMBING
J 2
(-5875 3650);
DISPLAY 0.872340 (-5875 3650);
PAINT GREEN (-5875 3650);
DISPLAY INVISIBLE (-5875 3650);
FORCEPROP 1 LAST HDL_TAP TRUE
J 2
(-6200 3475);
DISPLAY 0.872340 (-6200 3475);
DISPLAY INVISIBLE (-6200 3475);
FORCEPROP 1 LAST PATH I293
J 2
(-5873 3600);
DISPLAY 0.872340 (-5873 3600);
PAINT GREEN (-5873 3600);
DISPLAY INVISIBLE (-5873 3600);
FORCEADD TAP..1
R 2
(-5875 3400);
FORCEPROP 3 LASTPIN (-5825 3400) SIG_NAME M_J_CPU0_SB_CA<1>
J 0
(-5815 3410);
DISPLAY 0.659574 (-5815 3410);
PAINT MONO (-5815 3410);
DISPLAY INVISIBLE (-5815 3410);
FORCEPROP 1 LASTPIN (-5825 3400) BN 1
J 2
(-5813 3408);
DISPLAY 0.489362 (-5813 3408);
PAINT GREEN (-5813 3408);
FORCEPROP 2 LAST CDS_LIB mstr_standard
J 0
(-5875 3400);
DISPLAY 0.723404 (-5875 3400);
PAINT MONO (-5875 3400);
DISPLAY INVISIBLE (-5875 3400);
FORCEPROP 1 LAST BODY_TYPE PLUMBING
J 2
(-5875 3450);
DISPLAY 0.872340 (-5875 3450);
PAINT GREEN (-5875 3450);
DISPLAY INVISIBLE (-5875 3450);
FORCEPROP 1 LAST HDL_TAP TRUE
J 2
(-6200 3275);
DISPLAY 0.872340 (-6200 3275);
DISPLAY INVISIBLE (-6200 3275);
FORCEPROP 1 LAST PATH I294
J 2
(-5873 3400);
DISPLAY 0.872340 (-5873 3400);
PAINT GREEN (-5873 3400);
DISPLAY INVISIBLE (-5873 3400);
FORCEADD TAP..1
R 2
(-5875 3350);
FORCEPROP 3 LASTPIN (-5825 3350) SIG_NAME M_J_CPU0_SB_CA<2>
J 0
(-5815 3360);
DISPLAY 0.659574 (-5815 3360);
PAINT MONO (-5815 3360);
DISPLAY INVISIBLE (-5815 3360);
FORCEPROP 1 LASTPIN (-5825 3350) BN 2
J 2
(-5813 3358);
DISPLAY 0.489362 (-5813 3358);
PAINT GREEN (-5813 3358);
FORCEPROP 2 LAST CDS_LIB mstr_standard
J 0
(-5875 3350);
DISPLAY 0.723404 (-5875 3350);
PAINT MONO (-5875 3350);
DISPLAY INVISIBLE (-5875 3350);
FORCEPROP 1 LAST BODY_TYPE PLUMBING
J 2
(-5875 3400);
DISPLAY 0.872340 (-5875 3400);
PAINT GREEN (-5875 3400);
DISPLAY INVISIBLE (-5875 3400);
FORCEPROP 1 LAST HDL_TAP TRUE
J 2
(-6200 3225);
DISPLAY 0.872340 (-6200 3225);
DISPLAY INVISIBLE (-6200 3225);
FORCEPROP 1 LAST PATH I295
J 2
(-5873 3350);
DISPLAY 0.872340 (-5873 3350);
PAINT GREEN (-5873 3350);
DISPLAY INVISIBLE (-5873 3350);
FORCEADD TAP..1
R 2
(-5875 3450);
FORCEPROP 3 LASTPIN (-5825 3450) SIG_NAME M_J_CPU0_SB_CA<0>
J 0
(-5815 3460);
DISPLAY 0.659574 (-5815 3460);
PAINT MONO (-5815 3460);
DISPLAY INVISIBLE (-5815 3460);
FORCEPROP 1 LASTPIN (-5825 3450) BN 0
J 2
(-5813 3458);
DISPLAY 0.489362 (-5813 3458);
PAINT GREEN (-5813 3458);
FORCEPROP 2 LAST CDS_LIB mstr_standard
J 0
(-5875 3450);
DISPLAY 0.723404 (-5875 3450);
PAINT MONO (-5875 3450);
DISPLAY INVISIBLE (-5875 3450);
FORCEPROP 1 LAST BODY_TYPE PLUMBING
J 2
(-5875 3500);
DISPLAY 0.872340 (-5875 3500);
PAINT GREEN (-5875 3500);
DISPLAY INVISIBLE (-5875 3500);
FORCEPROP 1 LAST HDL_TAP TRUE
J 2
(-6200 3325);
DISPLAY 0.872340 (-6200 3325);
DISPLAY INVISIBLE (-6200 3325);
FORCEPROP 1 LAST PATH I296
J 2
(-5873 3450);
DISPLAY 0.872340 (-5873 3450);
PAINT GREEN (-5873 3450);
DISPLAY INVISIBLE (-5873 3450);
FORCEADD TAP..1
R 2
(-5875 3550);
FORCEPROP 3 LASTPIN (-5825 3550) SIG_NAME M_J_CPU0_SA_CA<6>
J 0
(-5815 3560);
DISPLAY 0.659574 (-5815 3560);
PAINT MONO (-5815 3560);
DISPLAY INVISIBLE (-5815 3560);
FORCEPROP 1 LASTPIN (-5825 3550) BN 6
J 2
(-5813 3558);
DISPLAY 0.489362 (-5813 3558);
PAINT GREEN (-5813 3558);
FORCEPROP 2 LAST CDS_LIB mstr_standard
J 0
(-5875 3550);
DISPLAY 0.723404 (-5875 3550);
PAINT MONO (-5875 3550);
DISPLAY INVISIBLE (-5875 3550);
FORCEPROP 1 LAST BODY_TYPE PLUMBING
J 2
(-5875 3600);
DISPLAY 0.872340 (-5875 3600);
PAINT GREEN (-5875 3600);
DISPLAY INVISIBLE (-5875 3600);
FORCEPROP 1 LAST HDL_TAP TRUE
J 2
(-6200 3425);
DISPLAY 0.872340 (-6200 3425);
DISPLAY INVISIBLE (-6200 3425);
FORCEPROP 1 LAST PATH I297
J 2
(-5873 3550);
DISPLAY 0.872340 (-5873 3550);
PAINT GREEN (-5873 3550);
DISPLAY INVISIBLE (-5873 3550);
FORCEADD TAP..1
R 2
(-5875 3200);
FORCEPROP 3 LASTPIN (-5825 3200) SIG_NAME M_J_CPU0_SB_CA<5>
J 0
(-5815 3210);
DISPLAY 0.659574 (-5815 3210);
PAINT MONO (-5815 3210);
DISPLAY INVISIBLE (-5815 3210);
FORCEPROP 1 LASTPIN (-5825 3200) BN 5
J 2
(-5813 3208);
DISPLAY 0.489362 (-5813 3208);
PAINT GREEN (-5813 3208);
FORCEPROP 2 LAST CDS_LIB mstr_standard
J 0
(-5875 3200);
DISPLAY 0.723404 (-5875 3200);
PAINT MONO (-5875 3200);
DISPLAY INVISIBLE (-5875 3200);
FORCEPROP 1 LAST BODY_TYPE PLUMBING
J 2
(-5875 3250);
DISPLAY 0.872340 (-5875 3250);
PAINT GREEN (-5875 3250);
DISPLAY INVISIBLE (-5875 3250);
FORCEPROP 1 LAST HDL_TAP TRUE
J 2
(-6200 3075);
DISPLAY 0.872340 (-6200 3075);
DISPLAY INVISIBLE (-6200 3075);
FORCEPROP 1 LAST PATH I298
J 2
(-5873 3200);
DISPLAY 0.872340 (-5873 3200);
PAINT GREEN (-5873 3200);
DISPLAY INVISIBLE (-5873 3200);
FORCEADD TAP..1
R 2
(-5875 3150);
FORCEPROP 3 LASTPIN (-5825 3150) SIG_NAME M_J_CPU0_SB_CA<6>
J 0
(-5815 3160);
DISPLAY 0.659574 (-5815 3160);
PAINT MONO (-5815 3160);
DISPLAY INVISIBLE (-5815 3160);
FORCEPROP 1 LASTPIN (-5825 3150) BN 6
J 2
(-5813 3158);
DISPLAY 0.489362 (-5813 3158);
PAINT GREEN (-5813 3158);
FORCEPROP 2 LAST CDS_LIB mstr_standard
J 0
(-5875 3150);
DISPLAY 0.723404 (-5875 3150);
PAINT MONO (-5875 3150);
DISPLAY INVISIBLE (-5875 3150);
FORCEPROP 1 LAST BODY_TYPE PLUMBING
J 2
(-5875 3200);
DISPLAY 0.872340 (-5875 3200);
PAINT GREEN (-5875 3200);
DISPLAY INVISIBLE (-5875 3200);
FORCEPROP 1 LAST HDL_TAP TRUE
J 2
(-6200 3025);
DISPLAY 0.872340 (-6200 3025);
DISPLAY INVISIBLE (-6200 3025);
FORCEPROP 1 LAST PATH I299
J 2
(-5873 3150);
DISPLAY 0.872340 (-5873 3150);
PAINT GREEN (-5873 3150);
DISPLAY INVISIBLE (-5873 3150);
FORCEADD TAP..1
R 2
(-5875 3250);
FORCEPROP 3 LASTPIN (-5825 3250) SIG_NAME M_J_CPU0_SB_CA<4>
J 0
(-5815 3260);
DISPLAY 0.659574 (-5815 3260);
PAINT MONO (-5815 3260);
DISPLAY INVISIBLE (-5815 3260);
FORCEPROP 1 LASTPIN (-5825 3250) BN 4
J 2
(-5813 3258);
DISPLAY 0.489362 (-5813 3258);
PAINT GREEN (-5813 3258);
FORCEPROP 2 LAST CDS_LIB mstr_standard
J 0
(-5875 3250);
DISPLAY 0.723404 (-5875 3250);
PAINT MONO (-5875 3250);
DISPLAY INVISIBLE (-5875 3250);
FORCEPROP 1 LAST BODY_TYPE PLUMBING
J 2
(-5875 3300);
DISPLAY 0.872340 (-5875 3300);
PAINT GREEN (-5875 3300);
DISPLAY INVISIBLE (-5875 3300);
FORCEPROP 1 LAST HDL_TAP TRUE
J 2
(-6200 3125);
DISPLAY 0.872340 (-6200 3125);
DISPLAY INVISIBLE (-6200 3125);
FORCEPROP 1 LAST PATH I300
J 2
(-5873 3250);
DISPLAY 0.872340 (-5873 3250);
PAINT GREEN (-5873 3250);
DISPLAY INVISIBLE (-5873 3250);
FORCEADD TAP..1
R 2
(-5875 3300);
FORCEPROP 3 LASTPIN (-5825 3300) SIG_NAME M_J_CPU0_SB_CA<3>
J 0
(-5815 3310);
DISPLAY 0.659574 (-5815 3310);
PAINT MONO (-5815 3310);
DISPLAY INVISIBLE (-5815 3310);
FORCEPROP 1 LASTPIN (-5825 3300) BN 3
J 2
(-5813 3308);
DISPLAY 0.489362 (-5813 3308);
PAINT GREEN (-5813 3308);
FORCEPROP 2 LAST CDS_LIB mstr_standard
J 0
(-5875 3300);
DISPLAY 0.723404 (-5875 3300);
PAINT MONO (-5875 3300);
DISPLAY INVISIBLE (-5875 3300);
FORCEPROP 1 LAST BODY_TYPE PLUMBING
J 2
(-5875 3350);
DISPLAY 0.872340 (-5875 3350);
PAINT GREEN (-5875 3350);
DISPLAY INVISIBLE (-5875 3350);
FORCEPROP 1 LAST HDL_TAP TRUE
J 2
(-6200 3175);
DISPLAY 0.872340 (-6200 3175);
DISPLAY INVISIBLE (-6200 3175);
FORCEPROP 1 LAST PATH I301
J 2
(-5873 3300);
DISPLAY 0.872340 (-5873 3300);
PAINT GREEN (-5873 3300);
DISPLAY INVISIBLE (-5873 3300);
FORCEADD OFFPAGE..2
R 2
(-6475 3875);
FORCEPROP 2 LAST $XR0 95 
J 0
(-6729 3875);
DISPLAY 0.638298 (-6729 3875);
PAINT MONO (-6729 3875);
FORCEPROP 2 LAST CDS_LIB standard
J 0
(-6475 3875);
DISPLAY INVISIBLE (-6475 3875);
FORCEPROP 1 LAST OFFPAGE TRUE
J 2
(-6800 3750);
DISPLAY 0.872340 (-6800 3750);
PAINT GREEN (-6800 3750);
DISPLAY INVISIBLE (-6800 3750);
FORCEPROP 1 LAST COMMENT_BODY TRUE
J 2
(-6430 3780);
DISPLAY 0.872340 (-6430 3780);
PAINT GREEN (-6430 3780);
DISPLAY INVISIBLE (-6430 3780);
FORCEPROP 2 LAST PATH I302
J 0
(-6750 3925);
DISPLAY 1.021277 (-6750 3925);
DISPLAY INVISIBLE (-6750 3925);
FORCEADD OFFPAGE..2
R 2
(-6475 3475);
FORCEPROP 2 LAST $XR0 95 
J 0
(-6729 3475);
DISPLAY 0.638298 (-6729 3475);
PAINT MONO (-6729 3475);
FORCEPROP 2 LAST CDS_LIB standard
J 0
(-6475 3475);
DISPLAY INVISIBLE (-6475 3475);
FORCEPROP 1 LAST OFFPAGE TRUE
J 2
(-6800 3350);
DISPLAY 0.872340 (-6800 3350);
PAINT GREEN (-6800 3350);
DISPLAY INVISIBLE (-6800 3350);
FORCEPROP 1 LAST COMMENT_BODY TRUE
J 2
(-6430 3380);
DISPLAY 0.872340 (-6430 3380);
PAINT GREEN (-6430 3380);
DISPLAY INVISIBLE (-6430 3380);
FORCEPROP 2 LAST PATH I303
J 0
(-6750 3525);
DISPLAY 1.021277 (-6750 3525);
DISPLAY INVISIBLE (-6750 3525);
FORCEADD OFFPAGE..2
R 2
(-6475 3000);
FORCEPROP 2 LAST $XR0 95 
J 0
(-6729 3000);
DISPLAY 0.638298 (-6729 3000);
PAINT MONO (-6729 3000);
FORCEPROP 2 LAST CDS_LIB standard
J 0
(-6475 3000);
DISPLAY INVISIBLE (-6475 3000);
FORCEPROP 1 LAST OFFPAGE TRUE
J 2
(-6800 2875);
DISPLAY 0.872340 (-6800 2875);
PAINT GREEN (-6800 2875);
DISPLAY INVISIBLE (-6800 2875);
FORCEPROP 1 LAST COMMENT_BODY TRUE
J 2
(-6430 2905);
DISPLAY 0.872340 (-6430 2905);
PAINT GREEN (-6430 2905);
DISPLAY INVISIBLE (-6430 2905);
FORCEPROP 2 LAST PATH I304
J 0
(-6750 3050);
DISPLAY 1.021277 (-6750 3050);
DISPLAY INVISIBLE (-6750 3050);
FORCEADD OFFPAGE..2
R 2
(-6475 2950);
FORCEPROP 2 LAST $XR0 95 
J 0
(-6729 2950);
DISPLAY 0.638298 (-6729 2950);
PAINT MONO (-6729 2950);
FORCEPROP 2 LAST CDS_LIB standard
J 0
(-6475 2950);
DISPLAY INVISIBLE (-6475 2950);
FORCEPROP 1 LAST OFFPAGE TRUE
J 2
(-6800 2825);
DISPLAY 0.872340 (-6800 2825);
PAINT GREEN (-6800 2825);
DISPLAY INVISIBLE (-6800 2825);
FORCEPROP 1 LAST COMMENT_BODY TRUE
J 2
(-6430 2855);
DISPLAY 0.872340 (-6430 2855);
PAINT GREEN (-6430 2855);
DISPLAY INVISIBLE (-6430 2855);
FORCEPROP 2 LAST PATH I305
J 0
(-6750 3000);
DISPLAY 1.021277 (-6750 3000);
DISPLAY INVISIBLE (-6750 3000);
FORCEADD OFFPAGE..2
R 2
(-6475 2850);
FORCEPROP 2 LAST $XR0 95 
J 0
(-6729 2850);
DISPLAY 0.638298 (-6729 2850);
PAINT MONO (-6729 2850);
FORCEPROP 2 LAST CDS_LIB standard
J 0
(-6475 2850);
DISPLAY INVISIBLE (-6475 2850);
FORCEPROP 1 LAST OFFPAGE TRUE
J 2
(-6800 2725);
DISPLAY 0.872340 (-6800 2725);
PAINT GREEN (-6800 2725);
DISPLAY INVISIBLE (-6800 2725);
FORCEPROP 1 LAST COMMENT_BODY TRUE
J 2
(-6430 2755);
DISPLAY 0.872340 (-6430 2755);
PAINT GREEN (-6430 2755);
DISPLAY INVISIBLE (-6430 2755);
FORCEPROP 2 LAST PATH I306
J 0
(-6750 2900);
DISPLAY 1.021277 (-6750 2900);
DISPLAY INVISIBLE (-6750 2900);
FORCEADD OFFPAGE..5
(-6475 2600);
FORCEPROP 2 LAST $XR0 95 
J 0
(-6729 2600);
DISPLAY 0.638298 (-6729 2600);
PAINT MONO (-6729 2600);
FORCEPROP 2 LAST CDS_LIB mstr_standard
J 0
(-6475 2600);
DISPLAY INVISIBLE (-6475 2600);
FORCEPROP 1 LAST OFFPAGE TRUE
J 0
(-6150 2475);
DISPLAY 0.872340 (-6150 2475);
PAINT GREEN (-6150 2475);
DISPLAY INVISIBLE (-6150 2475);
FORCEPROP 1 LAST COMMENT_BODY TRUE
J 0
(-6375 2525);
DISPLAY 0.872340 (-6375 2525);
PAINT GREEN (-6375 2525);
DISPLAY INVISIBLE (-6375 2525);
FORCEPROP 2 LAST PATH I307
J 0
(-6750 2650);
DISPLAY 1.021277 (-6750 2650);
DISPLAY INVISIBLE (-6750 2650);
FORCEADD OFFPAGE..2
R 2
(-6475 2800);
FORCEPROP 2 LAST $XR0 95 
J 0
(-6729 2800);
DISPLAY 0.638298 (-6729 2800);
PAINT MONO (-6729 2800);
FORCEPROP 2 LAST CDS_LIB standard
J 0
(-6475 2800);
DISPLAY INVISIBLE (-6475 2800);
FORCEPROP 1 LAST OFFPAGE TRUE
J 2
(-6800 2675);
DISPLAY 0.872340 (-6800 2675);
PAINT GREEN (-6800 2675);
DISPLAY INVISIBLE (-6800 2675);
FORCEPROP 1 LAST COMMENT_BODY TRUE
J 2
(-6430 2705);
DISPLAY 0.872340 (-6430 2705);
PAINT GREEN (-6430 2705);
DISPLAY INVISIBLE (-6430 2705);
FORCEPROP 2 LAST PATH I308
J 0
(-6750 2850);
DISPLAY 1.021277 (-6750 2850);
DISPLAY INVISIBLE (-6750 2850);
FORCEADD OFFPAGE..1
(-6475 2700);
FORCEPROP 2 LAST $XR0 95 
J 0
(-6726 2700);
DISPLAY 0.638298 (-6726 2700);
PAINT MONO (-6726 2700);
FORCEPROP 2 LAST CDS_LIB standard
J 0
(-6475 2700);
DISPLAY INVISIBLE (-6475 2700);
FORCEPROP 1 LAST OFFPAGE TRUE
J 0
(-6150 2575);
DISPLAY 0.872340 (-6150 2575);
PAINT GREEN (-6150 2575);
DISPLAY INVISIBLE (-6150 2575);
FORCEPROP 1 LAST COMMENT_BODY TRUE
J 0
(-6350 2600);
DISPLAY 0.872340 (-6350 2600);
PAINT GREEN (-6350 2600);
DISPLAY INVISIBLE (-6350 2600);
FORCEPROP 2 LAST PATH I309
J 0
(-6725 2750);
DISPLAY 1.021277 (-6725 2750);
DISPLAY INVISIBLE (-6725 2750);
FORCEADD OFFPAGE..2
R 2
(-6475 2500);
FORCEPROP 2 LAST $XR0 95 
J 0
(-6729 2500);
DISPLAY 0.638298 (-6729 2500);
PAINT MONO (-6729 2500);
FORCEPROP 2 LAST CDS_LIB standard
J 0
(-6475 2500);
DISPLAY INVISIBLE (-6475 2500);
FORCEPROP 1 LAST OFFPAGE TRUE
J 2
(-6800 2375);
DISPLAY 0.872340 (-6800 2375);
PAINT GREEN (-6800 2375);
DISPLAY INVISIBLE (-6800 2375);
FORCEPROP 1 LAST COMMENT_BODY TRUE
J 2
(-6430 2405);
DISPLAY 0.872340 (-6430 2405);
PAINT GREEN (-6430 2405);
DISPLAY INVISIBLE (-6430 2405);
FORCEPROP 2 LAST PATH I310
J 0
(-6750 2550);
DISPLAY 1.021277 (-6750 2550);
DISPLAY INVISIBLE (-6750 2550);
FORCEADD OFFPAGE..2
R 2
(-6475 2450);
FORCEPROP 2 LAST $XR0 95 
J 0
(-6729 2450);
DISPLAY 0.638298 (-6729 2450);
PAINT MONO (-6729 2450);
FORCEPROP 2 LAST CDS_LIB standard
J 0
(-6475 2450);
DISPLAY INVISIBLE (-6475 2450);
FORCEPROP 1 LAST OFFPAGE TRUE
J 2
(-6800 2325);
DISPLAY 0.872340 (-6800 2325);
PAINT GREEN (-6800 2325);
DISPLAY INVISIBLE (-6800 2325);
FORCEPROP 1 LAST COMMENT_BODY TRUE
J 2
(-6430 2355);
DISPLAY 0.872340 (-6430 2355);
PAINT GREEN (-6430 2355);
DISPLAY INVISIBLE (-6430 2355);
FORCEPROP 2 LAST PATH I311
J 0
(-6750 2500);
DISPLAY 1.021277 (-6750 2500);
DISPLAY INVISIBLE (-6750 2500);
FORCEADD OFFPAGE..1
(-6475 2350);
FORCEPROP 2 LAST $XR0 95 
J 0
(-6726 2350);
DISPLAY 0.638298 (-6726 2350);
PAINT MONO (-6726 2350);
FORCEPROP 2 LAST CDS_LIB standard
J 0
(-6475 2350);
DISPLAY INVISIBLE (-6475 2350);
FORCEPROP 1 LAST OFFPAGE TRUE
J 0
(-6150 2225);
DISPLAY 0.872340 (-6150 2225);
PAINT GREEN (-6150 2225);
DISPLAY INVISIBLE (-6150 2225);
FORCEPROP 1 LAST COMMENT_BODY TRUE
J 0
(-6350 2250);
DISPLAY 0.872340 (-6350 2250);
PAINT GREEN (-6350 2250);
DISPLAY INVISIBLE (-6350 2250);
FORCEPROP 2 LAST PATH I312
J 0
(-6725 2400);
DISPLAY 1.021277 (-6725 2400);
DISPLAY INVISIBLE (-6725 2400);
FORCEADD OFFPAGE..5
(-6475 2250);
FORCEPROP 2 LAST $XR0 95 
J 0
(-6729 2250);
DISPLAY 0.638298 (-6729 2250);
PAINT MONO (-6729 2250);
FORCEPROP 2 LAST CDS_LIB standard
J 0
(-6475 2250);
DISPLAY INVISIBLE (-6475 2250);
FORCEPROP 1 LAST OFFPAGE TRUE
J 0
(-6150 2125);
DISPLAY 0.872340 (-6150 2125);
PAINT GREEN (-6150 2125);
DISPLAY INVISIBLE (-6150 2125);
FORCEPROP 1 LAST COMMENT_BODY TRUE
J 0
(-6375 2175);
DISPLAY 0.872340 (-6375 2175);
PAINT GREEN (-6375 2175);
DISPLAY INVISIBLE (-6375 2175);
FORCEPROP 2 LAST PATH I313
J 0
(-6750 2300);
DISPLAY 1.021277 (-6750 2300);
DISPLAY INVISIBLE (-6750 2300);
FORCEADD Q_RES..1
(-6800 2150);
FORCEPROP 1 LAST LOCATION R384
J 0
(-7125 2150);
DISPLAY 0.489362 (-7125 2150);
PAINT SKYBLUE (-7125 2150);
FORCEPROP 0 LAST $SEC 1
J 0
(-6975 2200);
DISPLAY 0.680851 (-6975 2200);
PAINT MONO (-6975 2200);
DISPLAY INVISIBLE (-6975 2200);
FORCEPROP 0 LAST CDS_SEC 1
J 0
(-6975 2200);
DISPLAY 1.021277 (-6975 2200);
DISPLAY INVISIBLE (-6975 2200);
FORCEPROP 1 LASTPIN (-6900 2150) $PN 1
J 0
(-6888 2162);
DISPLAY 0.489362 (-6888 2162);
PAINT MONO (-6888 2162);
FORCEPROP 1 LASTPIN (-6700 2150) $PN 2
J 0
(-6738 2162);
DISPLAY 0.489362 (-6738 2162);
PAINT MONO (-6738 2162);
FORCEPROP 1 LAST PACK_TYPE 0402LF
J 0
(-7125 2125);
DISPLAY 0.489362 (-7125 2125);
PAINT SKYBLUE (-7125 2125);
FORCEPROP 1 LAST TOLERANCE 1%
J 0
(-6525 2150);
DISPLAY 0.489362 (-6525 2150);
PAINT SKYBLUE (-6525 2150);
FORCEPROP 1 LAST VALUE 15
J 2
(-6475 2150);
DISPLAY 0.489362 (-6475 2150);
PAINT SKYBLUE (-6475 2150);
FORCEPROP 1 LAST MATERIAL CHIP
J 0
(-6925 2275);
DISPLAY 0.638298 (-6925 2275);
PAINT SKYBLUE (-6925 2275);
DISPLAY INVISIBLE (-6925 2275);
FORCEPROP 1 LAST WATTAGE 1/16W
J 2
(-6575 2275);
DISPLAY 0.638298 (-6575 2275);
PAINT SKYBLUE (-6575 2275);
DISPLAY INVISIBLE (-6575 2275);
FORCEPROP 2 LAST CDS_LIB pure_quanta
J 0
(-6800 2150);
DISPLAY INVISIBLE (-6800 2150);
FORCEPROP 1 LAST PATH I314
J 0
(-6850 2300);
DISPLAY 0.978723 (-6850 2300);
PAINT WHITE (-6850 2300);
DISPLAY INVISIBLE (-6850 2300);
FORCEPROP 1 LAST PART_NUMBER CS01502FB03
J 0
(-6700 2125);
DISPLAY 0.489362 (-6700 2125);
PAINT SKYBLUE (-6700 2125);
DISPLAY INVISIBLE (-6700 2125);
FORCEADD OFFPAGE..1
(-7675 2150);
FORCEPROP 2 LAST $XR0 95 
J 0
(-7926 2150);
DISPLAY 0.638298 (-7926 2150);
PAINT MONO (-7926 2150);
FORCEPROP 2 LAST CDS_LIB mstr_standard
J 0
(-7675 2150);
DISPLAY INVISIBLE (-7675 2150);
FORCEPROP 1 LAST OFFPAGE TRUE
J 0
(-7350 2025);
DISPLAY 0.872340 (-7350 2025);
PAINT GREEN (-7350 2025);
DISPLAY INVISIBLE (-7350 2025);
FORCEPROP 1 LAST COMMENT_BODY TRUE
J 0
(-7550 2050);
DISPLAY 0.872340 (-7550 2050);
PAINT GREEN (-7550 2050);
DISPLAY INVISIBLE (-7550 2050);
FORCEPROP 2 LAST PATH I315
J 0
(-7950 2200);
DISPLAY 1.021277 (-7950 2200);
DISPLAY INVISIBLE (-7950 2200);
FORCEADD OFFPAGE..5
(-6475 2050);
FORCEPROP 2 LAST $XR0 95 
J 0
(-6729 2050);
DISPLAY 0.638298 (-6729 2050);
PAINT MONO (-6729 2050);
FORCEPROP 2 LAST CDS_LIB standard
J 0
(-6475 2050);
DISPLAY INVISIBLE (-6475 2050);
FORCEPROP 1 LAST OFFPAGE TRUE
J 0
(-6150 1925);
DISPLAY 0.872340 (-6150 1925);
PAINT GREEN (-6150 1925);
DISPLAY INVISIBLE (-6150 1925);
FORCEPROP 1 LAST COMMENT_BODY TRUE
J 0
(-6375 1975);
DISPLAY 0.872340 (-6375 1975);
PAINT GREEN (-6375 1975);
DISPLAY INVISIBLE (-6375 1975);
FORCEPROP 2 LAST PATH I316
J 0
(-6750 2100);
DISPLAY 1.021277 (-6750 2100);
DISPLAY INVISIBLE (-6750 2100);
FORCEADD QUANTA_TITLE_BLOCK_C..1
(0 0);
FORCEPROP 0 LAST CDS_CON_LAST_MODIFIED Thu Sep 14 16:11:50 2023
J 0
(-1885 15);
DISPLAY INVISIBLE (-1885 15);
FORCEPROP 1 LAST CUSTOM_TXT_CDS <CON_LAST_MODIFIED>
J 0
(-1885 15);
DISPLAY 0.978723 (-1885 15);
FORCEPROP 2 LAST CUSTOM_TXT_CDS <XR_PAGE_TITLE>
J 0
(-7890 5250);
DISPLAY 0.638298 (-7890 5250);
PAINT PINK (-7890 5250);
DISPLAY INVISIBLE (-7890 5250);
FORCEPROP 1 LAST CUSTOM_TXT_CDS <NAME_2>
J 0
(-3175 50);
FORCEPROP 1 LAST CUSTOM_TXT_CDS <NAME_1>
J 0
(-3175 175);
FORCEPROP 1 LAST CUSTOM_TXT_CDS <Q_NUMBER>
J 0
(-1403 103);
DISPLAY 1.212766 (-1403 103);
FORCEPROP 1 LAST CUSTOM_TXT_CDS <Q_PROJ>
J 0
(-2382 102);
DISPLAY 1.212766 (-2382 102);
FORCEPROP 1 LAST CUSTOM_TXT_CDS <Q_REV>
J 0
(-184 103);
DISPLAY 1.212766 (-184 103);
FORCEPROP 1 LAST CUSTOM_TXT_CDS <CON_PAGE_NUM> OF <CON_TOTAL_PAGES>
J 0
(-446 18);
DISPLAY 0.978723 (-446 18);
FORCEPROP 1 LAST Q_TITLE CPU0 DDR CHJ
J 0
(-9300 50);
DISPLAY 2.446809 (-9300 50);
PAINT GREEN (-9300 50);
FORCEPROP 1 LAST CDS_LMAN_SYM_OUTLINE -9475,6775,100,-125
J 0
(0 0);
DISPLAY 0.468085 (0 0);
PAINT GREEN (0 0);
DISPLAY INVISIBLE (0 0);
FORCEPROP 2 LAST CDS_LIB pure_quanta
J 0
(0 0);
DISPLAY INVISIBLE (0 0);
FORCEPROP 2 LAST PAGE_BORDER TRUE
J 0
(-7890 5250);
DISPLAY 0.638298 (-7890 5250);
PAINT PINK (-7890 5250);
DISPLAY INVISIBLE (-7890 5250);
FORCEPROP 2 LAST CDS_XR_PAGE_TITLE CR-19 : @T6G_MB_LIB.T6G(SCH_1):PAGE19
J 0
(-7890 5250);
DISPLAY 0.638298 (-7890 5250);
PAINT PINK (-7890 5250);
DISPLAY INVISIBLE (-7890 5250);
FORCEPROP 1 LAST Q_DEPT BU9
J 1
(-3763 49);
DISPLAY 1.957447 (-3763 49);
PAINT GREEN (-3763 49);
DISPLAY INVISIBLE (-3763 49);
FORCEPROP 1 LAST COMMENT_BODY TRUE
J 0
(12 -13);
DISPLAY 0.978723 (12 -13);
PAINT GREEN (12 -13);
DISPLAY INVISIBLE (12 -13);
FORCEADD CAD_NOTE..1
(-7650 2475);
FORCEPROP 0 LAST L1 R1949 PLACE CLOSE TO CPU < 25MM
J 0
(-7800 2350);
DISPLAY 0.617021 (-7800 2350);
PAINT WHITE (-7800 2350);
FORCEPROP 2 LAST CDS_LIB pure_quanta_power
J 0
(-7650 2475);
DISPLAY INVISIBLE (-7650 2475);
FORCEPROP 1 LAST COMMENT_BODY TRUE
J 0
(-7625 2575);
DISPLAY 0.574468 (-7625 2575);
PAINT WHITE (-7625 2575);
DISPLAY INVISIBLE (-7625 2575);
WIRE 17 -1 (-3200 5275)(-3200 5225);
WIRE 17 -1 (-3200 5325)(-3200 5275);
WIRE 17 -1 (-3200 5125)(-3200 5225);
WIRE 17 -1 (-3200 5075)(-3200 5125);
WIRE 17 -1 (-3200 5375)(-3200 5325);
WIRE 17 -1 (-3200 5425)(-3200 5375);
WIRE 17 -1 (-3200 5025)(-3200 5075);
WIRE 17 -1 (-3200 4975)(-3200 5025);
WIRE 17 -1 (-3200 5475)(-3200 5425);
WIRE 17 -1 (-3200 5525)(-3200 5475);
WIRE 17 -1 (-3200 4975)(-3200 4925);
WIRE 17 -1 (-3200 4925)(-3200 4875);
WIRE 17 -1 (-3200 5575)(-3200 5525);
WIRE 17 -1 (-3200 5675)(-3200 5575);
WIRE 17 -1 (-3200 4875)(-3200 4825);
WIRE 17 -1 (-3200 4825)(-3200 4775);
WIRE 17 -1 (-3200 5725)(-3200 5675);
WIRE 17 -1 (-3200 5775)(-3200 5725);
WIRE 17 -1 (-3200 4775)(-3200 4675);
WIRE 17 -1 (-3200 4675)(-3200 4625);
WIRE 17 -1 (-3200 5825)(-3200 5775);
WIRE 17 -1 (-3200 5875)(-3200 5825);
WIRE 17 -1 (-3200 4625)(-3200 4575);
WIRE 17 -1 (-3200 4575)(-3200 4525);
WIRE 17 -1 (-3200 5925)(-3200 5875);
WIRE 17 -1 (-3200 5975)(-3200 5925);
WIRE 17 -1 (-3200 4475)(-3200 4525);
WIRE 17 -1 (-3200 4425)(-3200 4475);
WIRE 17 -1 (-3200 6025)(-3200 5975);
WIRE 17 -1 (-3200 6025)(-2575 6025);
FORCEPROP 2 LAST SIG_NAME M_J_CPU0_SA_DQ<31:0>
J 2
(-2635 6035);
DISPLAY 0.489362 (-2635 6035);
WIRE 17 -1 (-3200 4175)(-3200 4125);
WIRE 17 -1 (-3200 4225)(-3200 4175);
WIRE 17 -1 (-3200 4125)(-3200 4075);
WIRE 17 -1 (-3200 4075)(-3200 4025);
WIRE 17 -1 (-3200 4225)(-2575 4225);
FORCEPROP 2 LAST SIG_NAME M_J_CPU0_SB_DQ<31:0>
J 2
(-2635 4235);
DISPLAY 0.489362 (-2635 4235);
WIRE 17 -1 (-3200 4375)(-3200 4425);
WIRE 17 -1 (-3200 4325)(-3200 4375);
WIRE 17 -1 (-3200 3175)(-3200 3125);
WIRE 17 -1 (-3200 3175)(-3200 3225);
WIRE 17 -1 (-3200 3125)(-3200 3075);
WIRE 17 -1 (-3200 3075)(-3200 3025);
WIRE 17 -1 (-3200 3225)(-3200 3275);
WIRE 17 -1 (-3200 3275)(-3200 3325);
WIRE 17 -1 (-3200 3025)(-3200 2975);
WIRE 17 -1 (-3200 2975)(-3200 2875);
WIRE 17 -1 (-3200 3325)(-3200 3425);
WIRE 17 -1 (-3200 3475)(-3200 3425);
WIRE 17 -1 (-3200 2875)(-3200 2825);
WIRE 17 -1 (-3200 2825)(-3200 2775);
WIRE 17 -1 (-3200 3525)(-3200 3475);
WIRE 17 -1 (-3200 3575)(-3200 3525);
WIRE 17 -1 (-3200 2775)(-3200 2725);
WIRE 17 -1 (-3200 2675)(-3200 2725);
WIRE 17 -1 (-3200 3625)(-3200 3575);
WIRE 17 -1 (-3200 3675)(-3200 3625);
WIRE 17 -1 (-3200 2625)(-3200 2675);
WIRE 17 -1 (-3200 2575)(-3200 2625);
WIRE 17 -1 (-3200 3725)(-3200 3675);
WIRE 17 -1 (-3200 3775)(-3200 3725);
WIRE 17 -1 (-3200 2525)(-3200 2575);
WIRE 17 -1 (-3200 3875)(-3200 3775);
WIRE 17 -1 (-3200 3925)(-3200 3875);
WIRE 17 -1 (-3200 3975)(-3200 3925);
WIRE 17 -1 (-3200 4025)(-3200 3975);
WIRE 17 -1 (-3200 2075)(-3200 2125);
WIRE 17 -1 (-3200 2125)(-3200 2175);
WIRE 17 -1 (-3200 2175)(-3200 2225);
WIRE 17 -1 (-3200 2225)(-3200 2275);
WIRE 17 -1 (-3200 2325)(-3200 2275);
WIRE 17 -1 (-3200 2325)(-3200 2375);
WIRE 17 -1 (-3200 2425)(-3200 2375);
WIRE 17 -1 (-3200 2425)(-3200 2450);
WIRE 17 -1 (-3200 2450)(-2700 2450);
FORCEPROP 2 LAST SIG_NAME M_J_CPU0_SA_CB<7:0>
J 2
(-2700 2460);
DISPLAY 0.489362 (-2700 2460);
WIRE 17 -1 (-3200 1625)(-3200 1675);
WIRE 17 -1 (-3200 1675)(-3200 1725);
WIRE 17 -1 (-3200 1725)(-3200 1775);
WIRE 17 -1 (-3200 1775)(-3200 1825);
WIRE 17 -1 (-3200 1875)(-3200 1825);
WIRE 17 -1 (-3200 1875)(-3200 1925);
WIRE 17 -1 (-3200 1975)(-3200 1925);
WIRE 17 -1 (-3200 1975)(-3200 2000);
WIRE 17 -1 (-3200 2000)(-2700 2000);
FORCEPROP 2 LAST SIG_NAME M_J_CPU0_SB_CB<7:0>
J 2
(-2700 2010);
DISPLAY 0.489362 (-2700 2010);
WIRE 17 -1 (-5725 5825)(-5725 5725);
WIRE 17 -1 (-5725 5925)(-5725 5825);
WIRE 17 -1 (-5725 5725)(-5725 5625);
WIRE 17 -1 (-5725 5525)(-5725 5625);
WIRE 17 -1 (-5725 6025)(-5725 5925);
WIRE 17 -1 (-5725 6025)(-6525 6025);
FORCEPROP 2 LAST SIG_NAME M_J_CPU0_SA_DQS_DP<9:0>
J 2
(-5960 6035);
DISPLAY 0.489362 (-5960 6035);
WIRE 17 -1 (-5725 5325)(-5725 5425);
WIRE 17 -1 (-5725 5325)(-5725 5225);
WIRE 17 -1 (-5725 5425)(-5725 5525);
WIRE 17 -1 (-5725 5225)(-5725 5125);
WIRE 17 -1 (-5925 5275)(-5925 5175);
WIRE 17 -1 (-5925 5275)(-5925 5375);
WIRE 17 -1 (-5925 5175)(-5925 5075);
WIRE 17 -1 (-5925 5375)(-5925 5475);
WIRE 17 -1 (-5925 5475)(-5925 5575);
WIRE 17 -1 (-5925 5675)(-5925 5575);
WIRE 17 -1 (-5925 5775)(-5925 5675);
WIRE 17 -1 (-5925 5875)(-5925 5775);
WIRE 17 -1 (-5925 5975)(-5925 5875);
FORCEPROP 2 LAST SIG_NAME M_J_CPU0_SA_DQS_DN<9:0>
J 2
(-5960 5985);
DISPLAY 0.489362 (-5960 5985);
WIRE 17 -1 (-5725 4775)(-5725 4675);
WIRE 17 -1 (-5725 4875)(-5725 4775);
WIRE 17 -1 (-5725 4675)(-5725 4575);
WIRE 17 -1 (-5725 4475)(-5725 4575);
WIRE 17 -1 (-5725 4975)(-5725 4875);
WIRE 17 -1 (-5725 4975)(-6525 4975);
FORCEPROP 2 LAST SIG_NAME M_J_CPU0_SB_DQS_DP<9:0>
J 2
(-5960 4985);
DISPLAY 0.489362 (-5960 4985);
WIRE 17 -1 (-5725 4275)(-5725 4175);
WIRE 17 -1 (-5725 4275)(-5725 4375);
WIRE 17 -1 (-5725 4175)(-5725 4075);
WIRE 17 -1 (-5725 4375)(-5725 4475);
WIRE 17 -1 (-5925 4225)(-5925 4125);
WIRE 17 -1 (-5925 4225)(-5925 4325);
WIRE 17 -1 (-5925 4125)(-5925 4025);
WIRE 17 -1 (-5925 4325)(-5925 4425);
WIRE 17 -1 (-5925 4425)(-5925 4525);
WIRE 17 -1 (-5925 4625)(-5925 4525);
WIRE 17 -1 (-5925 4725)(-5925 4625);
WIRE 17 -1 (-5925 4825)(-5925 4725);
WIRE 17 -1 (-5925 4925)(-5925 4825);
FORCEPROP 2 LAST SIG_NAME M_J_CPU0_SB_DQS_DN<9:0>
J 2
(-5960 4935);
DISPLAY 0.489362 (-5960 4935);
WIRE 17 -1 (-5925 3175)(-5925 3225);
WIRE 17 -1 (-5925 3225)(-5925 3275);
WIRE 17 -1 (-5925 3275)(-5925 3325);
WIRE 17 -1 (-5925 3325)(-5925 3375);
WIRE 17 -1 (-5925 3375)(-5925 3425);
WIRE 17 -1 (-5925 3425)(-5925 3475);
WIRE 17 -1 (-5925 3475)(-6425 3475);
FORCEPROP 2 LAST SIG_NAME M_J_CPU0_SB_CA<6:0>
J 0
(-6425 3485);
DISPLAY 0.489362 (-6425 3485);
WIRE 17 -1 (-5925 3675)(-5925 3725);
WIRE 17 -1 (-5925 3625)(-5925 3675);
WIRE 17 -1 (-5925 3725)(-5925 3775);
WIRE 17 -1 (-5925 3775)(-5925 3825);
WIRE 17 -1 (-5925 3575)(-5925 3625);
WIRE 17 -1 (-5925 3825)(-5925 3875);
WIRE 17 -1 (-5925 3875)(-6425 3875);
FORCEPROP 2 LAST SIG_NAME M_J_CPU0_SA_CA<6:0>
J 0
(-6425 3885);
DISPLAY 0.489362 (-6425 3885);
WIRE 17 -1 (-5925 5975)(-6525 5975);
WIRE 17 -1 (-5925 4925)(-6525 4925);
WIRE 16 -1 (-7625 2150)(-6900 2150);
FORCEPROP 2 LAST SIG_NAME M_J_CPU0_ALERT_N
J 0
(-7585 2160);
DISPLAY 0.489362 (-7585 2160);
WIRE 16 -1 (-6700 2150)(-5325 2150);
FORCEPROP 2 LAST SIG_NAME M_J_CPU0_ALERT_R_N
J 0
(-6410 2160);
DISPLAY 0.489362 (-6410 2160);
FORCEPROP 2 LASTPROP $XRERR UNIQUE?
J 0
(-6650 2160);
DISPLAY 0.638298 (-6650 2160);
PAINT MONO (-6650 2160);
DISPLAY INVISIBLE (-6650 2160);
WIRE 16 -1 (-6425 1200)(-5325 1200);
FORCEPROP 2 LAST SIG_NAME TP_M_J_CPU0_SA_TEST39J
J 0
(-6410 1210);
DISPLAY 0.489362 (-6410 1210);
FORCEPROP 2 LASTPROP $XRERR UNIQUE?
J 0
(-6665 1200);
DISPLAY 0.638298 (-6665 1200);
PAINT MONO (-6665 1200);
DISPLAY INVISIBLE (-6665 1200);
WIRE 16 -1 (-6425 3000)(-5325 3000);
FORCEPROP 2 LAST SIG_NAME M_J_CPU0_CLK_DP<0>
J 0
(-6425 3010);
DISPLAY 0.489362 (-6425 3010);
WIRE 16 -1 (-6425 2950)(-5325 2950);
FORCEPROP 2 LAST SIG_NAME M_J_CPU0_CLK_DN<0>
J 0
(-6425 2960);
DISPLAY 0.489362 (-6425 2960);
WIRE 16 -1 (-6425 2850)(-5325 2850);
FORCEPROP 2 LAST SIG_NAME M_J_CPU0_SA_CS_N<0>
J 0
(-6425 2860);
DISPLAY 0.489362 (-6425 2860);
WIRE 16 -1 (-6425 2600)(-5325 2600);
FORCEPROP 2 LAST SIG_NAME M_J_CPU0_SA_PAR
J 0
(-6425 2610);
DISPLAY 0.489362 (-6425 2610);
WIRE 16 -1 (-6425 2800)(-5325 2800);
FORCEPROP 2 LAST SIG_NAME M_J_CPU0_SA_CS_N<1>
J 0
(-6425 2810);
DISPLAY 0.489362 (-6425 2810);
WIRE 16 -1 (-6425 2700)(-5325 2700);
FORCEPROP 2 LAST SIG_NAME M_J_CPU0_SA_RSP<0>
J 0
(-6425 2710);
DISPLAY 0.489362 (-6425 2710);
WIRE 16 -1 (-6425 2500)(-5325 2500);
FORCEPROP 2 LAST SIG_NAME M_J_CPU0_SB_CS_N<0>
J 0
(-6425 2510);
DISPLAY 0.489362 (-6425 2510);
WIRE 16 -1 (-6425 2450)(-5325 2450);
FORCEPROP 2 LAST SIG_NAME M_J_CPU0_SB_CS_N<1>
J 0
(-6425 2460);
DISPLAY 0.489362 (-6425 2460);
WIRE 16 -1 (-6425 2350)(-5325 2350);
FORCEPROP 2 LAST SIG_NAME M_J_CPU0_SB_RSP<0>
J 0
(-6425 2360);
DISPLAY 0.489362 (-6425 2360);
WIRE 16 -1 (-6425 2250)(-5325 2250);
FORCEPROP 2 LAST SIG_NAME M_J_CPU0_SB_PAR
J 0
(-6425 2260);
DISPLAY 0.489362 (-6425 2260);
WIRE 16 -1 (-6425 2050)(-5325 2050);
FORCEPROP 2 LAST SIG_NAME M_J_CPU0_RESET_N
J 0
(-6425 2060);
DISPLAY 0.489362 (-6425 2060);
WIRE 16 -1 (-5825 3600)(-5325 3600);
WIRE 16 -1 (-5825 3550)(-5325 3550);
WIRE 16 -1 (-5825 3850)(-5325 3850);
WIRE 16 -1 (-5825 3800)(-5325 3800);
WIRE 16 -1 (-5825 3750)(-5325 3750);
WIRE 16 -1 (-5825 3700)(-5325 3700);
WIRE 16 -1 (-5825 3650)(-5325 3650);
WIRE 16 -1 (-5825 3450)(-5325 3450);
WIRE 16 -1 (-5825 3400)(-5325 3400);
WIRE 16 -1 (-5825 3350)(-5325 3350);
WIRE 16 -1 (-5825 3300)(-5325 3300);
WIRE 16 -1 (-5825 3250)(-5325 3250);
WIRE 16 -1 (-5825 3200)(-5325 3200);
WIRE 16 -1 (-5825 3150)(-5325 3150);
WIRE 16 -1 (-5825 4000)(-5325 4000);
WIRE 16 -1 (-5625 4050)(-5325 4050);
WIRE 16 -1 (-5825 4500)(-5325 4500);
WIRE 16 -1 (-5825 4900)(-5325 4900);
WIRE 16 -1 (-5825 5050)(-5325 5050);
WIRE 16 -1 (-5825 4800)(-5325 4800);
WIRE 16 -1 (-5825 4700)(-5325 4700);
WIRE 16 -1 (-5825 4600)(-5325 4600);
WIRE 16 -1 (-5825 4400)(-5325 4400);
WIRE 16 -1 (-5825 4300)(-5325 4300);
WIRE 16 -1 (-5825 4200)(-5325 4200);
WIRE 16 -1 (-5825 4100)(-5325 4100);
WIRE 16 -1 (-5625 4450)(-5325 4450);
WIRE 16 -1 (-5625 4550)(-5325 4550);
WIRE 16 -1 (-5625 4350)(-5325 4350);
WIRE 16 -1 (-5625 4250)(-5325 4250);
WIRE 16 -1 (-5625 4150)(-5325 4150);
WIRE 16 -1 (-5625 5100)(-5325 5100);
WIRE 16 -1 (-5625 4950)(-5325 4950);
WIRE 16 -1 (-5625 4850)(-5325 4850);
WIRE 16 -1 (-5625 4750)(-5325 4750);
WIRE 16 -1 (-5625 4650)(-5325 4650);
WIRE 16 -1 (-5825 5550)(-5325 5550);
WIRE 16 -1 (-5825 5450)(-5325 5450);
WIRE 16 -1 (-5825 5250)(-5325 5250);
WIRE 16 -1 (-5825 5950)(-5325 5950);
WIRE 16 -1 (-5825 5850)(-5325 5850);
WIRE 16 -1 (-5825 5750)(-5325 5750);
WIRE 16 -1 (-5825 5650)(-5325 5650);
WIRE 16 -1 (-5825 5350)(-5325 5350);
WIRE 16 -1 (-5825 5150)(-5325 5150);
WIRE 16 -1 (-5625 5600)(-5325 5600);
WIRE 16 -1 (-5625 5200)(-5325 5200);
WIRE 16 -1 (-5625 5500)(-5325 5500);
WIRE 16 -1 (-5625 5400)(-5325 5400);
WIRE 16 -1 (-5625 5300)(-5325 5300);
WIRE 16 -1 (-5625 6000)(-5325 6000);
WIRE 16 -1 (-5625 5900)(-5325 5900);
WIRE 16 -1 (-5625 5800)(-5325 5800);
WIRE 16 -1 (-5625 5700)(-5325 5700);
WIRE 16 -1 (-3725 1950)(-3300 1950);
WIRE 16 -1 (-3725 1900)(-3300 1900);
WIRE 16 -1 (-3725 1850)(-3300 1850);
WIRE 16 -1 (-3725 1800)(-3300 1800);
WIRE 16 -1 (-3725 1750)(-3300 1750);
WIRE 16 -1 (-3725 1700)(-3300 1700);
WIRE 16 -1 (-3725 1650)(-3300 1650);
WIRE 16 -1 (-3725 1600)(-3300 1600);
WIRE 16 -1 (-3725 2400)(-3300 2400);
WIRE 16 -1 (-3725 2350)(-3300 2350);
WIRE 16 -1 (-3725 2300)(-3300 2300);
WIRE 16 -1 (-3725 2250)(-3300 2250);
WIRE 16 -1 (-3725 2200)(-3300 2200);
WIRE 16 -1 (-3725 2150)(-3300 2150);
WIRE 16 -1 (-3725 2100)(-3300 2100);
WIRE 16 -1 (-3725 2050)(-3300 2050);
WIRE 16 -1 (-3725 3050)(-3300 3050);
WIRE 16 -1 (-3725 3000)(-3300 3000);
WIRE 16 -1 (-3725 2950)(-3300 2950);
WIRE 16 -1 (-3725 2850)(-3300 2850);
WIRE 16 -1 (-3725 2800)(-3300 2800);
WIRE 16 -1 (-3725 2750)(-3300 2750);
WIRE 16 -1 (-3725 2700)(-3300 2700);
WIRE 16 -1 (-3725 2650)(-3300 2650);
WIRE 16 -1 (-3725 2600)(-3300 2600);
WIRE 16 -1 (-3725 2550)(-3300 2550);
WIRE 16 -1 (-3725 2500)(-3300 2500);
WIRE 16 -1 (-3725 3850)(-3300 3850);
WIRE 16 -1 (-3725 3900)(-3300 3900);
WIRE 16 -1 (-3725 3950)(-3300 3950);
WIRE 16 -1 (-3725 4050)(-3300 4050);
WIRE 16 -1 (-3725 4000)(-3300 4000);
WIRE 16 -1 (-3725 3750)(-3300 3750);
WIRE 16 -1 (-3725 3700)(-3300 3700);
WIRE 16 -1 (-3725 3650)(-3300 3650);
WIRE 16 -1 (-3725 3600)(-3300 3600);
WIRE 16 -1 (-3725 3550)(-3300 3550);
WIRE 16 -1 (-3725 3500)(-3300 3500);
WIRE 16 -1 (-3725 3450)(-3300 3450);
WIRE 16 -1 (-3725 3400)(-3300 3400);
WIRE 16 -1 (-3725 3300)(-3300 3300);
WIRE 16 -1 (-3725 3250)(-3300 3250);
WIRE 16 -1 (-3725 3200)(-3300 3200);
WIRE 16 -1 (-3725 3150)(-3300 3150);
WIRE 16 -1 (-3725 3100)(-3300 3100);
WIRE 16 -1 (-3725 4300)(-3300 4300);
WIRE 16 -1 (-3725 4200)(-3300 4200);
WIRE 16 -1 (-3725 4800)(-3300 4800);
WIRE 16 -1 (-3725 5100)(-3300 5100);
WIRE 16 -1 (-3725 5050)(-3300 5050);
WIRE 16 -1 (-3725 5000)(-3300 5000);
WIRE 16 -1 (-3725 4950)(-3300 4950);
WIRE 16 -1 (-3725 4900)(-3300 4900);
WIRE 16 -1 (-3725 4850)(-3300 4850);
WIRE 16 -1 (-3725 4750)(-3300 4750);
WIRE 16 -1 (-3725 4650)(-3300 4650);
WIRE 16 -1 (-3725 4600)(-3300 4600);
WIRE 16 -1 (-3725 4550)(-3300 4550);
WIRE 16 -1 (-3725 4500)(-3300 4500);
WIRE 16 -1 (-3725 4450)(-3300 4450);
WIRE 16 -1 (-3725 4400)(-3300 4400);
WIRE 16 -1 (-3725 4350)(-3300 4350);
WIRE 16 -1 (-3725 4150)(-3300 4150);
WIRE 16 -1 (-3725 4100)(-3300 4100);
WIRE 16 -1 (-3725 6000)(-3300 6000);
WIRE 16 -1 (-3725 5950)(-3300 5950);
WIRE 16 -1 (-3725 5900)(-3300 5900);
WIRE 16 -1 (-3725 5850)(-3300 5850);
WIRE 16 -1 (-3725 5800)(-3300 5800);
WIRE 16 -1 (-3725 5750)(-3300 5750);
WIRE 16 -1 (-3725 5700)(-3300 5700);
WIRE 16 -1 (-3725 5650)(-3300 5650);
WIRE 16 -1 (-3725 5550)(-3300 5550);
WIRE 16 -1 (-3725 5500)(-3300 5500);
WIRE 16 -1 (-3725 5450)(-3300 5450);
WIRE 16 -1 (-3725 5400)(-3300 5400);
WIRE 16 -1 (-3725 5350)(-3300 5350);
WIRE 16 -1 (-3725 5300)(-3300 5300);
WIRE 16 -1 (-3725 5250)(-3300 5250);
WIRE 16 -1 (-3725 5200)(-3300 5200);
QUIT
